FILE_TYPE = MACRO_DRAWING;
SET COLOR_WIRE YELLOW;
SET COLOR_PROP MONO;
SET COLOR_DOT WHITE;
SET COLOR_ARC YELLOW;
SET COLOR_BODY GREEN;
SET COLOR_NOTE MONO;
SET PROP_DISPLAY VALUE;
SET PAGE_NUMBER P194;
FORCEADD GND..1
(-1450 2875);
FORCEPROP 3 LASTPIN (-1450 2925) SIG_NAME GND\g
J 0
(-1440 2935);
DISPLAY 0.659574 (-1440 2935);
PAINT MONO (-1440 2935);
DISPLAY INVISIBLE (-1440 2935);
FORCEPROP 1 LAST VOLTAGE 0
J 0
(-1450 2875);
PAINT SKYBLUE (-1450 2875);
DISPLAY INVISIBLE (-1450 2875);
FORCEPROP 2 LAST CDS_LIB mstr_symbols
J 0
(-1450 2875);
PAINT ORANGE (-1450 2875);
DISPLAY INVISIBLE (-1450 2875);
FORCEPROP 2 LAST BOM_COST PROC_VRD_VCCIN_CPU0
J 0
(-1825 2950);
DISPLAY 1.446809 (-1825 2950);
PAINT MONO (-1825 2950);
DISPLAY INVISIBLE (-1825 2950);
FORCEPROP 1 LAST SIZE 1B
J 0
(-1375 2825);
DISPLAY 1.723404 (-1375 2825);
PAINT GREEN (-1375 2825);
DISPLAY INVISIBLE (-1375 2825);
FORCEPROP 1 LAST BODY_TYPE PLUMBING
J 0
(-1495 2832);
DISPLAY 0.340426 (-1495 2832);
PAINT GREEN (-1495 2832);
DISPLAY INVISIBLE (-1495 2832);
FORCEPROP 1 LAST PATH I100
J 0
(-1375 2875);
DISPLAY 0.872340 (-1375 2875);
PAINT AQUA (-1375 2875);
DISPLAY INVISIBLE (-1375 2875);
FORCEPROP 2 LAST ROOM PVSA_CPU0_DECAP_VR
J 0
(-2000 2950);
DISPLAY 1.936170 (-2000 2950);
PAINT ORANGE (-2000 2950);
DISPLAY INVISIBLE (-2000 2950);
FORCEPROP 1 LAST HDL_POWER GND
J 0
(-1450 3025);
DISPLAY 1.723404 (-1450 3025);
PAINT GREEN (-1450 3025);
DISPLAY INVISIBLE (-1450 3025);
FORCEADD CAPP..1
(-1450 3150);
FORCEPROP 1 LAST LOCATION C3N14
J 0
(-1400 3250);
DISPLAY 0.617021 (-1400 3250);
PAINT AQUA (-1400 3250);
FORCEPROP 1 LAST PART_NUMBER 699013-049
J 0
(-1400 2950);
DISPLAY 0.617021 (-1400 2950);
PAINT BLUE (-1400 2950);
FORCEPROP 1 LAST VALUE 470UF
J 0
(-1400 3200);
DISPLAY 0.617021 (-1400 3200);
PAINT SKYBLUE (-1400 3200);
FORCEPROP 1 LAST TOLERANCE 20%
J 0
(-1400 3150);
DISPLAY 0.617021 (-1400 3150);
PAINT SKYBLUE (-1400 3150);
FORCEPROP 1 LAST PACK_TYPE 3018
J 0
(-1400 3000);
DISPLAY 0.617021 (-1400 3000);
PAINT SKYBLUE (-1400 3000);
FORCEPROP 1 LAST MATERIAL ALUM
J 0
(-1400 3050);
DISPLAY 0.617021 (-1400 3050);
PAINT SKYBLUE (-1400 3050);
FORCEPROP 1 LASTPIN (-1450 3050) $PN 2
J 0
(-1440 3035);
DISPLAY 0.617021 (-1440 3035);
PAINT ORANGE (-1440 3035);
FORCEPROP 1 LASTPIN (-1450 3250) $PN 1
J 0
(-1440 3235);
DISPLAY 0.617021 (-1440 3235);
PAINT ORANGE (-1440 3235);
FORCEPROP 1 LAST VOLTAGE 2.5V
J 0
(-1400 3100);
PAINT SKYBLUE (-1400 3100);
DISPLAY INVISIBLE (-1400 3100);
FORCEPROP 2 LAST SEC_TYPE 3018
J 0
(-1400 3350);
DISPLAY 1.021277 (-1400 3350);
PAINT ORANGE (-1400 3350);
DISPLAY INVISIBLE (-1400 3350);
FORCEPROP 2 LAST CDS_LIB mstr_discrete
J 0
(-1450 3150);
PAINT ORANGE (-1450 3150);
DISPLAY INVISIBLE (-1450 3150);
FORCEPROP 2 LAST BOM_COST PROC_VRD_VCCIN_CPU0
J 0
(-1400 3300);
PAINT MONO (-1400 3300);
DISPLAY INVISIBLE (-1400 3300);
FORCEPROP 2 LAST SEC 1
J 0
(-1400 3350);
PAINT MONO (-1400 3350);
DISPLAY INVISIBLE (-1400 3350);
FORCEPROP 2 LAST CDS_LOCATION C3N14
J 0
(-1400 3250);
DISPLAY 0.617021 (-1400 3250);
PAINT AQUA (-1400 3250);
DISPLAY INVISIBLE (-1400 3250);
FORCEPROP 1 LAST PATH I101
J 0
(-1400 3300);
DISPLAY 0.978723 (-1400 3300);
PAINT ORANGE (-1400 3300);
DISPLAY INVISIBLE (-1400 3300);
FORCEPROP 2 LAST ROOM P0V95_MCP_CPU0_DECAP_VR
J 0
(-1400 3275);
PAINT MONO (-1400 3275);
DISPLAY INVISIBLE (-1400 3275);
FORCEADD VCC_CORE..1
(-1450 3425);
FORCEPROP 3 LASTPIN (-1450 3375) SIG_NAME PVCCIOMCP_CPU0\g
J 0
(-1440 3385);
DISPLAY 0.659574 (-1440 3385);
PAINT MONO (-1440 3385);
DISPLAY INVISIBLE (-1440 3385);
FORCEPROP 1 LAST HDL_POWER PVCCIOMCP_CPU0
J 1
(-1450 3475);
DISPLAY 0.617021 (-1450 3475);
PAINT GREEN (-1450 3475);
FORCEPROP 0 LAST VOLTAGE +0.95
J 0
(-1450 3575);
DISPLAY 1.021277 (-1450 3575);
PAINT SKYBLUE (-1450 3575);
DISPLAY INVISIBLE (-1450 3575);
FORCEPROP 2 LAST CDS_LIB mstr_symbols
J 0
(-1450 3425);
PAINT ORANGE (-1450 3425);
DISPLAY INVISIBLE (-1450 3425);
FORCEPROP 1 LAST PATH I102
J 0
(-1400 3450);
DISPLAY 0.872340 (-1400 3450);
PAINT AQUA (-1400 3450);
DISPLAY INVISIBLE (-1400 3450);
FORCEADD GND..1
(-7375 1225);
FORCEPROP 3 LASTPIN (-7375 1275) SIG_NAME GND\g
J 0
(-7365 1285);
DISPLAY 0.659574 (-7365 1285);
PAINT MONO (-7365 1285);
DISPLAY INVISIBLE (-7365 1285);
FORCEPROP 1 LAST VOLTAGE 0.0V
J 0
(-7420 1182);
DISPLAY 0.340426 (-7420 1182);
PAINT SKYBLUE (-7420 1182);
DISPLAY INVISIBLE (-7420 1182);
FORCEPROP 1 LAST SIZE 1B
J 0
(-7300 1175);
DISPLAY 1.404255 (-7300 1175);
PAINT AQUA (-7300 1175);
DISPLAY INVISIBLE (-7300 1175);
FORCEPROP 2 LAST CDS_LIB mstr_symbols
J 0
(-7375 1225);
PAINT MONO (-7375 1225);
DISPLAY INVISIBLE (-7375 1225);
FORCEPROP 1 LAST BODY_TYPE PLUMBING
J 0
(-7420 1182);
DISPLAY 0.340426 (-7420 1182);
PAINT GREEN (-7420 1182);
DISPLAY INVISIBLE (-7420 1182);
FORCEPROP 1 LAST PATH I110
J 0
(-7300 1225);
DISPLAY 0.872340 (-7300 1225);
PAINT AQUA (-7300 1225);
DISPLAY INVISIBLE (-7300 1225);
FORCEPROP 1 LAST HDL_POWER GND
J 0
(-7375 1375);
PAINT GREEN (-7375 1375);
DISPLAY INVISIBLE (-7375 1375);
FORCEADD GND..1
(-7225 675);
FORCEPROP 3 LASTPIN (-7225 725) SIG_NAME GND\g
J 0
(-7215 735);
DISPLAY 0.659574 (-7215 735);
PAINT MONO (-7215 735);
DISPLAY INVISIBLE (-7215 735);
FORCEPROP 1 LAST VOLTAGE 0.0V
J 0
(-7270 632);
DISPLAY 0.340426 (-7270 632);
PAINT SKYBLUE (-7270 632);
DISPLAY INVISIBLE (-7270 632);
FORCEPROP 2 LAST CDS_LIB mstr_symbols
J 0
(-7225 675);
PAINT MONO (-7225 675);
DISPLAY INVISIBLE (-7225 675);
FORCEPROP 1 LAST SIZE 1B
J 0
(-7150 625);
DISPLAY 1.404255 (-7150 625);
PAINT AQUA (-7150 625);
DISPLAY INVISIBLE (-7150 625);
FORCEPROP 1 LAST BODY_TYPE PLUMBING
J 0
(-7270 632);
DISPLAY 0.340426 (-7270 632);
PAINT GREEN (-7270 632);
DISPLAY INVISIBLE (-7270 632);
FORCEPROP 1 LAST PATH I111
J 0
(-7150 675);
DISPLAY 0.872340 (-7150 675);
PAINT AQUA (-7150 675);
DISPLAY INVISIBLE (-7150 675);
FORCEPROP 1 LAST HDL_POWER GND
J 0
(-7225 825);
PAINT GREEN (-7225 825);
DISPLAY INVISIBLE (-7225 825);
FORCEADD OFFPAGE..4
(-5275 625);
FORCEPROP 2 LAST $XR0 21 
J 0
(-5089 625);
DISPLAY 0.638298 (-5089 625);
PAINT MONO (-5089 625);
FORCEPROP 2 LAST $XR1 201 
J 0
(-4999 625);
DISPLAY 0.638298 (-4999 625);
PAINT MONO (-4999 625);
FORCEPROP 2 LAST $XR2 211 
J 0
(-4879 625);
DISPLAY 0.638298 (-4879 625);
PAINT MONO (-4879 625);
FORCEPROP 2 LAST CDS_LIB mstr_standard
J 0
(-5275 625);
PAINT MONO (-5275 625);
DISPLAY INVISIBLE (-5275 625);
FORCEPROP 2 LAST ROOM P0V95_FPGA_CPU0_VR
J 0
(-5825 700);
DISPLAY 1.361702 (-5825 700);
PAINT ORANGE (-5825 700);
DISPLAY INVISIBLE (-5825 700);
FORCEPROP 1 LAST OFFPAGE TRUE
J 0
(-4950 500);
DISPLAY 0.872340 (-4950 500);
PAINT GREEN (-4950 500);
DISPLAY INVISIBLE (-4950 500);
FORCEPROP 1 LAST COMMENT_BODY TRUE
J 0
(-5300 525);
DISPLAY 0.872340 (-5300 525);
PAINT GREEN (-5300 525);
DISPLAY INVISIBLE (-5300 525);
FORCEPROP 2 LAST PATH I114
J 0
(-5100 700);
DISPLAY 1.021277 (-5100 700);
PAINT ORANGE (-5100 700);
DISPLAY INVISIBLE (-5100 700);
FORCEADD OFFPAGE..1
R 2
(-5300 1325);
FORCEPROP 2 LAST $XR0 138 
J 0
(-5114 1325);
DISPLAY 0.638298 (-5114 1325);
PAINT MONO (-5114 1325);
FORCEPROP 2 LAST $XR1 159 
J 0
(-4994 1325);
DISPLAY 0.638298 (-4994 1325);
PAINT MONO (-4994 1325);
FORCEPROP 2 LAST $XR2 211 
J 0
(-4874 1325);
DISPLAY 0.638298 (-4874 1325);
PAINT MONO (-4874 1325);
FORCEPROP 2 LAST $XR3 213 
J 0
(-4754 1325);
DISPLAY 0.638298 (-4754 1325);
PAINT MONO (-4754 1325);
FORCEPROP 2 LAST $XR4 235 
J 0
(-4634 1325);
DISPLAY 0.638298 (-4634 1325);
PAINT MONO (-4634 1325);
FORCEPROP 2 LAST $XR5 193 
J 0
(-4514 1325);
DISPLAY 0.638298 (-4514 1325);
PAINT MONO (-4514 1325);
FORCEPROP 2 LAST $XR6 201 
J 0
(-4394 1325);
DISPLAY 0.638298 (-4394 1325);
PAINT MONO (-4394 1325);
FORCEPROP 2 LAST $XR7 206 
J 0
(-4274 1325);
DISPLAY 0.638298 (-4274 1325);
PAINT MONO (-4274 1325);
FORCEPROP 2 LAST $XR8 215 
J 0
(-4154 1325);
DISPLAY 0.638298 (-4154 1325);
PAINT MONO (-4154 1325);
FORCEPROP 2 LAST $XR9 218 
J 0
(-4994 1289);
DISPLAY 0.638298 (-4994 1289);
PAINT MONO (-4994 1289);
FORCEPROP 2 LAST $XR10 223 
J 0
(-4874 1289);
DISPLAY 0.638298 (-4874 1289);
PAINT MONO (-4874 1289);
FORCEPROP 2 LAST $XR11 226 
J 0
(-4754 1289);
DISPLAY 0.638298 (-4754 1289);
PAINT MONO (-4754 1289);
FORCEPROP 2 LAST CDS_LIB mstr_standard
J 0
(-5300 1325);
PAINT ORANGE (-5300 1325);
DISPLAY INVISIBLE (-5300 1325);
FORCEPROP 2 LAST ROOM P0V95_FPGA_CPU0_VR
J 0
(-5725 1400);
DISPLAY 1.361702 (-5725 1400);
PAINT ORANGE (-5725 1400);
DISPLAY INVISIBLE (-5725 1400);
FORCEPROP 1 LAST OFFPAGE TRUE
J 2
(-5625 1200);
DISPLAY 1.170213 (-5625 1200);
PAINT GREEN (-5625 1200);
DISPLAY INVISIBLE (-5625 1200);
FORCEPROP 1 LAST COMMENT_BODY TRUE
J 2
(-5425 1225);
DISPLAY 1.170213 (-5425 1225);
PAINT GREEN (-5425 1225);
DISPLAY INVISIBLE (-5425 1225);
FORCEPROP 2 LAST PATH I116
J 0
(-4625 1400);
DISPLAY 1.021277 (-4625 1400);
PAINT ORANGE (-4625 1400);
DISPLAY INVISIBLE (-4625 1400);
FORCEADD P12V_STBY..1
(-7175 4075);
FORCEPROP 3 LASTPIN (-7175 4025) SIG_NAME P12V_STBY\g
J 0
(-7165 4035);
DISPLAY 0.659574 (-7165 4035);
PAINT MONO (-7165 4035);
DISPLAY INVISIBLE (-7165 4035);
FORCEPROP 1 LAST VOLTAGE 12.0V
J 0
(-7220 4032);
DISPLAY 0.340426 (-7220 4032);
PAINT SKYBLUE (-7220 4032);
DISPLAY INVISIBLE (-7220 4032);
FORCEPROP 1 LAST SIZE 1B
J 0
(-7130 4097);
DISPLAY 0.340426 (-7130 4097);
PAINT GREEN (-7130 4097);
DISPLAY INVISIBLE (-7130 4097);
FORCEPROP 2 LAST CDS_LIB mstr_symbols
J 0
(-7175 4075);
PAINT MONO (-7175 4075);
DISPLAY INVISIBLE (-7175 4075);
FORCEPROP 1 LAST BODY_TYPE PLUMBING
J 0
(-7220 4032);
DISPLAY 0.340426 (-7220 4032);
PAINT GREEN (-7220 4032);
DISPLAY INVISIBLE (-7220 4032);
FORCEPROP 1 LAST PATH I119
J 0
(-7130 4077);
DISPLAY 0.340426 (-7130 4077);
PAINT GREEN (-7130 4077);
DISPLAY INVISIBLE (-7130 4077);
FORCEPROP 1 LAST HDL_POWER P12V_STBY
J 0
(-7475 3950);
DISPLAY 0.872340 (-7475 3950);
PAINT ORANGE (-7475 3950);
DISPLAY INVISIBLE (-7475 3950);
FORCEADD P3V3_STBY..1
(-5725 3900);
FORCEPROP 3 LASTPIN (-5725 3850) SIG_NAME P3V3_STBY\g
J 0
(-5715 3860);
DISPLAY 0.659574 (-5715 3860);
PAINT MONO (-5715 3860);
DISPLAY INVISIBLE (-5715 3860);
FORCEPROP 1 LAST VOLTAGE +3.3V
J 0
(-5525 4050);
DISPLAY 1.021277 (-5525 4050);
PAINT SKYBLUE (-5525 4050);
DISPLAY INVISIBLE (-5525 4050);
FORCEPROP 1 LAST SIZE 1B
J 0
(-5680 3922);
DISPLAY 0.340426 (-5680 3922);
PAINT GREEN (-5680 3922);
DISPLAY INVISIBLE (-5680 3922);
FORCEPROP 2 LAST CDS_LIB mstr_symbols
J 0
(-5725 3900);
PAINT MONO (-5725 3900);
DISPLAY INVISIBLE (-5725 3900);
FORCEPROP 1 LAST BODY_TYPE PLUMBING
J 0
(-5770 3857);
DISPLAY 0.340426 (-5770 3857);
PAINT GREEN (-5770 3857);
DISPLAY INVISIBLE (-5770 3857);
FORCEPROP 1 LAST PATH I120
J 0
(-5680 3902);
DISPLAY 0.340426 (-5680 3902);
PAINT GREEN (-5680 3902);
DISPLAY INVISIBLE (-5680 3902);
FORCEPROP 1 LAST HDL_POWER P3V3_STBY
J 0
(-6025 3775);
DISPLAY 0.872340 (-6025 3775);
PAINT ORANGE (-6025 3775);
DISPLAY INVISIBLE (-6025 3775);
FORCEADD P5V_STBY..1
(-5775 3200);
FORCEPROP 3 LASTPIN (-5775 3150) SIG_NAME P5V_STBY\g
J 0
(-5765 3160);
DISPLAY 0.659574 (-5765 3160);
PAINT MONO (-5765 3160);
DISPLAY INVISIBLE (-5765 3160);
FORCEPROP 1 LAST VOLTAGE +5.0V
J 0
(-5575 3350);
DISPLAY 1.021277 (-5575 3350);
PAINT SKYBLUE (-5575 3350);
DISPLAY INVISIBLE (-5575 3350);
FORCEPROP 1 LAST SIZE 1B
J 0
(-5730 3222);
DISPLAY 0.340426 (-5730 3222);
PAINT GREEN (-5730 3222);
DISPLAY INVISIBLE (-5730 3222);
FORCEPROP 2 LAST CDS_LIB mstr_symbols
J 0
(-5775 3200);
PAINT MONO (-5775 3200);
DISPLAY INVISIBLE (-5775 3200);
FORCEPROP 1 LAST BODY_TYPE PLUMBING
J 0
(-5820 3157);
DISPLAY 0.340426 (-5820 3157);
PAINT GREEN (-5820 3157);
DISPLAY INVISIBLE (-5820 3157);
FORCEPROP 1 LAST PATH I121
J 0
(-5730 3202);
DISPLAY 0.340426 (-5730 3202);
PAINT GREEN (-5730 3202);
DISPLAY INVISIBLE (-5730 3202);
FORCEPROP 1 LAST HDL_POWER P5V_STBY
J 0
(-6075 3075);
DISPLAY 0.872340 (-6075 3075);
PAINT ORANGE (-6075 3075);
DISPLAY INVISIBLE (-6075 3075);
FORCEADD OFFPAGE..3
(-5300 1275);
FORCEPROP 2 LAST $XR0 138 
J 0
(-5086 1275);
DISPLAY 0.638298 (-5086 1275);
PAINT MONO (-5086 1275);
FORCEPROP 2 LAST $XR1 159 
J 0
(-5086 1239);
DISPLAY 0.638298 (-5086 1239);
PAINT MONO (-5086 1239);
FORCEPROP 2 LAST $XR2 193 
J 0
(-4966 1239);
DISPLAY 0.638298 (-4966 1239);
PAINT MONO (-4966 1239);
FORCEPROP 2 LAST $XR3 201 
J 0
(-4846 1239);
DISPLAY 0.638298 (-4846 1239);
PAINT MONO (-4846 1239);
FORCEPROP 2 LAST $XR4 206 
J 0
(-4726 1239);
DISPLAY 0.638298 (-4726 1239);
PAINT MONO (-4726 1239);
FORCEPROP 2 LAST $XR5 211 
J 0
(-4606 1239);
DISPLAY 0.638298 (-4606 1239);
PAINT MONO (-4606 1239);
FORCEPROP 2 LAST $XR6 213 
J 0
(-4486 1239);
DISPLAY 0.638298 (-4486 1239);
PAINT MONO (-4486 1239);
FORCEPROP 2 LAST $XR7 215 
J 0
(-4366 1239);
DISPLAY 0.638298 (-4366 1239);
PAINT MONO (-4366 1239);
FORCEPROP 2 LAST $XR8 218 
J 0
(-4246 1239);
DISPLAY 0.638298 (-4246 1239);
PAINT MONO (-4246 1239);
FORCEPROP 2 LAST $XR9 223 
J 0
(-4126 1239);
DISPLAY 0.638298 (-4126 1239);
PAINT MONO (-4126 1239);
FORCEPROP 2 LAST $XR10 226 
J 0
(-4606 1275);
DISPLAY 0.638298 (-4606 1275);
PAINT MONO (-4606 1275);
FORCEPROP 2 LAST $XR11 235 
J 0
(-4486 1275);
DISPLAY 0.638298 (-4486 1275);
PAINT MONO (-4486 1275);
FORCEPROP 2 LAST CDS_LIB mstr_standard
J 0
(-5300 1275);
PAINT MONO (-5300 1275);
DISPLAY INVISIBLE (-5300 1275);
FORCEPROP 2 LAST ROOM P0V95_FPGA_CPU0_VR
J 0
(-5700 1350);
DISPLAY 1.361702 (-5700 1350);
PAINT ORANGE (-5700 1350);
DISPLAY INVISIBLE (-5700 1350);
FORCEPROP 1 LAST OFFPAGE TRUE
J 0
(-4975 1150);
DISPLAY 1.170213 (-4975 1150);
PAINT GREEN (-4975 1150);
DISPLAY INVISIBLE (-4975 1150);
FORCEPROP 1 LAST COMMENT_BODY TRUE
J 0
(-5350 1175);
DISPLAY 1.170213 (-5350 1175);
PAINT GREEN (-5350 1175);
DISPLAY INVISIBLE (-5350 1175);
FORCEPROP 2 LAST PATH I123
J 0
(-5100 1350);
DISPLAY 1.021277 (-5100 1350);
PAINT ORANGE (-5100 1350);
DISPLAY INVISIBLE (-5100 1350);
FORCEADD OFFPAGE..1
(-8000 1125);
FORCEPROP 2 LAST $XR0 39 
J 0
(-8221 1125);
DISPLAY 0.638298 (-8221 1125);
PAINT MONO (-8221 1125);
FORCEPROP 2 LAST ROOM PVSA_CPU0_VSENSE_VR
J 0
(-8400 1200);
PAINT ORANGE (-8400 1200);
DISPLAY INVISIBLE (-8400 1200);
FORCEPROP 2 LAST CDS_LIB mstr_standard
J 0
(-8000 1125);
PAINT MONO (-8000 1125);
DISPLAY INVISIBLE (-8000 1125);
FORCEPROP 2 LAST BOM_COST PROC_VRD_VCCIN_CPU0
J 0
(-7675 1175);
PAINT MONO (-7675 1175);
DISPLAY INVISIBLE (-7675 1175);
FORCEPROP 1 LAST OFFPAGE TRUE
J 0
(-7675 1000);
DISPLAY 0.872340 (-7675 1000);
PAINT GREEN (-7675 1000);
DISPLAY INVISIBLE (-7675 1000);
FORCEPROP 1 LAST COMMENT_BODY TRUE
J 0
(-7875 1025);
DISPLAY 0.872340 (-7875 1025);
PAINT GREEN (-7875 1025);
DISPLAY INVISIBLE (-7875 1025);
FORCEPROP 2 LAST PATH I124
J 0
(-7950 1200);
DISPLAY 1.021277 (-7950 1200);
PAINT ORANGE (-7950 1200);
DISPLAY INVISIBLE (-7950 1200);
FORCEADD OFFPAGE..1
(-8000 1075);
FORCEPROP 2 LAST $XR0 39 
J 0
(-8221 1075);
DISPLAY 0.638298 (-8221 1075);
PAINT MONO (-8221 1075);
FORCEPROP 2 LAST ROOM PVSA_CPU0_VSENSE_VR
J 0
(-8400 1150);
PAINT ORANGE (-8400 1150);
DISPLAY INVISIBLE (-8400 1150);
FORCEPROP 2 LAST CDS_LIB mstr_standard
J 0
(-8000 1075);
PAINT MONO (-8000 1075);
DISPLAY INVISIBLE (-8000 1075);
FORCEPROP 2 LAST BOM_COST PROC_VRD_VCCIN_CPU0
J 0
(-7675 1125);
PAINT MONO (-7675 1125);
DISPLAY INVISIBLE (-7675 1125);
FORCEPROP 1 LAST OFFPAGE TRUE
J 0
(-7675 950);
DISPLAY 0.872340 (-7675 950);
PAINT GREEN (-7675 950);
DISPLAY INVISIBLE (-7675 950);
FORCEPROP 1 LAST COMMENT_BODY TRUE
J 0
(-7875 975);
DISPLAY 0.872340 (-7875 975);
PAINT GREEN (-7875 975);
DISPLAY INVISIBLE (-7875 975);
FORCEPROP 2 LAST PATH I125
J 0
(-7950 1150);
DISPLAY 1.021277 (-7950 1150);
PAINT ORANGE (-7950 1150);
DISPLAY INVISIBLE (-7950 1150);
FORCEADD GND..1
(-5350 1525);
FORCEPROP 3 LASTPIN (-5350 1575) SIG_NAME GND\g
J 0
(-5340 1585);
DISPLAY 0.659574 (-5340 1585);
PAINT MONO (-5340 1585);
DISPLAY INVISIBLE (-5340 1585);
FORCEPROP 1 LAST VOLTAGE 0.0V
J 0
(-5395 1482);
DISPLAY 0.340426 (-5395 1482);
PAINT SKYBLUE (-5395 1482);
DISPLAY INVISIBLE (-5395 1482);
FORCEPROP 2 LAST CDS_LIB mstr_symbols
J 0
(-5350 1525);
PAINT MONO (-5350 1525);
DISPLAY INVISIBLE (-5350 1525);
FORCEPROP 1 LAST SIZE 1B
J 0
(-5275 1475);
DISPLAY 1.404255 (-5275 1475);
PAINT AQUA (-5275 1475);
DISPLAY INVISIBLE (-5275 1475);
FORCEPROP 1 LAST BODY_TYPE PLUMBING
J 0
(-5395 1482);
DISPLAY 0.340426 (-5395 1482);
PAINT GREEN (-5395 1482);
DISPLAY INVISIBLE (-5395 1482);
FORCEPROP 1 LAST PATH I127
J 0
(-5275 1525);
DISPLAY 0.872340 (-5275 1525);
PAINT AQUA (-5275 1525);
DISPLAY INVISIBLE (-5275 1525);
FORCEPROP 1 LAST HDL_POWER GND
J 0
(-5350 1675);
PAINT GREEN (-5350 1675);
DISPLAY INVISIBLE (-5350 1675);
FORCEADD VCC_CORE..1
(-3900 3925);
FORCEPROP 3 LASTPIN (-3900 3875) SIG_NAME PVCCMCP_CPU0\g
J 0
(-3890 3885);
DISPLAY 0.659574 (-3890 3885);
PAINT MONO (-3890 3885);
DISPLAY INVISIBLE (-3890 3885);
FORCEPROP 1 LAST HDL_POWER PVCCMCP_CPU0
J 1
(-3900 3975);
DISPLAY 0.617021 (-3900 3975);
PAINT GREEN (-3900 3975);
FORCEPROP 2 LAST BOM_COST PVMCP_FPGA_CPU0_VR
J 0
(-3900 4025);
DISPLAY 2.340426 (-3900 4025);
PAINT WHITE (-3900 4025);
DISPLAY INVISIBLE (-3900 4025);
FORCEPROP 2 LAST CDS_LIB mstr_symbols
J 0
(-3900 3925);
PAINT MONO (-3900 3925);
DISPLAY INVISIBLE (-3900 3925);
FORCEPROP 1 LAST PATH I130
J 0
(-3850 3950);
DISPLAY 0.872340 (-3850 3950);
PAINT AQUA (-3850 3950);
DISPLAY INVISIBLE (-3850 3950);
FORCEPROP 2 LAST ROOM PVMCP_FPGA_CPU0_VR
J 0
(-3900 4025);
DISPLAY 3.127660 (-3900 4025);
PAINT WHITE (-3900 4025);
DISPLAY INVISIBLE (-3900 4025);
FORCEADD OFFPAGE..4
(-5375 2025);
FORCEPROP 2 LAST $XR0 190 
J 0
(-5189 2025);
DISPLAY 0.638298 (-5189 2025);
PAINT MONO (-5189 2025);
FORCEPROP 2 LAST ROOM P0V95_FPGA_CPU0_VR
J 0
(-5925 2100);
DISPLAY 1.361702 (-5925 2100);
PAINT ORANGE (-5925 2100);
DISPLAY INVISIBLE (-5925 2100);
FORCEPROP 2 LAST CDS_LIB mstr_standard
J 0
(-5375 2025);
PAINT MONO (-5375 2025);
DISPLAY INVISIBLE (-5375 2025);
FORCEPROP 1 LAST OFFPAGE TRUE
J 0
(-5050 1900);
DISPLAY 0.872340 (-5050 1900);
PAINT GREEN (-5050 1900);
DISPLAY INVISIBLE (-5050 1900);
FORCEPROP 1 LAST COMMENT_BODY TRUE
J 0
(-5400 1925);
DISPLAY 0.872340 (-5400 1925);
PAINT GREEN (-5400 1925);
DISPLAY INVISIBLE (-5400 1925);
FORCEPROP 2 LAST PATH I131
J 0
(-5175 2075);
DISPLAY 1.021277 (-5175 2075);
PAINT ORANGE (-5175 2075);
DISPLAY INVISIBLE (-5175 2075);
FORCEADD OFFPAGE..2
(-5350 1975);
FORCEPROP 2 LAST $XR0 190 
J 0
(-5161 1975);
DISPLAY 0.638298 (-5161 1975);
PAINT MONO (-5161 1975);
FORCEPROP 2 LAST ROOM P0V95_FPGA_CPU0_VR
J 0
(-5775 2050);
DISPLAY 1.361702 (-5775 2050);
PAINT ORANGE (-5775 2050);
DISPLAY INVISIBLE (-5775 2050);
FORCEPROP 2 LAST CDS_LIB mstr_standard
J 0
(-5350 1975);
PAINT MONO (-5350 1975);
DISPLAY INVISIBLE (-5350 1975);
FORCEPROP 1 LAST OFFPAGE TRUE
J 0
(-5025 1850);
DISPLAY 1.170213 (-5025 1850);
PAINT GREEN (-5025 1850);
DISPLAY INVISIBLE (-5025 1850);
FORCEPROP 1 LAST COMMENT_BODY TRUE
J 0
(-5395 1880);
DISPLAY 1.170213 (-5395 1880);
PAINT GREEN (-5395 1880);
DISPLAY INVISIBLE (-5395 1880);
FORCEPROP 2 LAST PATH I132
J 0
(-5150 2025);
DISPLAY 1.021277 (-5150 2025);
PAINT ORANGE (-5150 2025);
DISPLAY INVISIBLE (-5150 2025);
FORCEADD OFFPAGE..2
(-5350 2325);
FORCEPROP 2 LAST $XR0 191 
J 0
(-5161 2325);
DISPLAY 0.638298 (-5161 2325);
PAINT MONO (-5161 2325);
FORCEPROP 2 LAST CDS_LIB mstr_standard
J 0
(-5350 2325);
PAINT MONO (-5350 2325);
DISPLAY INVISIBLE (-5350 2325);
FORCEPROP 2 LAST ROOM P0V95_FPGA_CPU0_VR
J 0
(-5775 2400);
DISPLAY 1.361702 (-5775 2400);
PAINT ORANGE (-5775 2400);
DISPLAY INVISIBLE (-5775 2400);
FORCEPROP 1 LAST OFFPAGE TRUE
J 0
(-5025 2200);
DISPLAY 1.170213 (-5025 2200);
PAINT GREEN (-5025 2200);
DISPLAY INVISIBLE (-5025 2200);
FORCEPROP 1 LAST COMMENT_BODY TRUE
J 0
(-5395 2230);
DISPLAY 1.170213 (-5395 2230);
PAINT GREEN (-5395 2230);
DISPLAY INVISIBLE (-5395 2230);
FORCEPROP 2 LAST PATH I133
J 0
(-5150 2375);
DISPLAY 1.021277 (-5150 2375);
PAINT ORANGE (-5150 2375);
DISPLAY INVISIBLE (-5150 2375);
FORCEADD OFFPAGE..4
(-5350 2375);
FORCEPROP 2 LAST $XR0 191 
J 0
(-5164 2375);
DISPLAY 0.638298 (-5164 2375);
PAINT MONO (-5164 2375);
FORCEPROP 2 LAST CDS_LIB mstr_standard
J 0
(-5350 2375);
PAINT MONO (-5350 2375);
DISPLAY INVISIBLE (-5350 2375);
FORCEPROP 2 LAST ROOM P0V95_FPGA_CPU0_VR
J 0
(-5900 2450);
DISPLAY 1.361702 (-5900 2450);
PAINT ORANGE (-5900 2450);
DISPLAY INVISIBLE (-5900 2450);
FORCEPROP 1 LAST OFFPAGE TRUE
J 0
(-5025 2250);
DISPLAY 0.872340 (-5025 2250);
PAINT GREEN (-5025 2250);
DISPLAY INVISIBLE (-5025 2250);
FORCEPROP 1 LAST COMMENT_BODY TRUE
J 0
(-5375 2275);
DISPLAY 0.872340 (-5375 2275);
PAINT GREEN (-5375 2275);
DISPLAY INVISIBLE (-5375 2275);
FORCEPROP 2 LAST PATH I134
J 0
(-5150 2425);
DISPLAY 1.021277 (-5150 2425);
PAINT ORANGE (-5150 2425);
DISPLAY INVISIBLE (-5150 2425);
FORCEADD VCC_CORE..1
(-4175 4050);
FORCEPROP 3 LASTPIN (-4175 4000) SIG_NAME P1V8_MCP_CPU0\g
J 0
(-4165 4010);
DISPLAY 0.659574 (-4165 4010);
PAINT MONO (-4165 4010);
DISPLAY INVISIBLE (-4165 4010);
FORCEPROP 1 LAST HDL_POWER P1V8_MCP_CPU0
J 1
(-4175 4100);
DISPLAY 0.617021 (-4175 4100);
PAINT GREEN (-4175 4100);
FORCEPROP 2 LAST CDS_LIB mstr_symbols
J 0
(-4175 4050);
PAINT ORANGE (-4175 4050);
DISPLAY INVISIBLE (-4175 4050);
FORCEPROP 1 LAST PATH I141
J 0
(-4125 4075);
DISPLAY 0.872340 (-4125 4075);
PAINT AQUA (-4125 4075);
DISPLAY INVISIBLE (-4125 4075);
FORCEADD VCC_CORE..1
(-1450 1350);
FORCEPROP 3 LASTPIN (-1450 1300) SIG_NAME P1V8_MCP_CPU0\g
J 0
(-1440 1310);
DISPLAY 0.659574 (-1440 1310);
PAINT MONO (-1440 1310);
DISPLAY INVISIBLE (-1440 1310);
FORCEPROP 1 LAST HDL_POWER P1V8_MCP_CPU0
J 1
(-1450 1400);
DISPLAY 0.617021 (-1450 1400);
PAINT GREEN (-1450 1400);
FORCEPROP 2 LAST CDS_LIB mstr_symbols
J 0
(-1450 1350);
PAINT ORANGE (-1450 1350);
DISPLAY INVISIBLE (-1450 1350);
FORCEPROP 1 LAST PATH I142
J 0
(-1400 1375);
DISPLAY 0.872340 (-1400 1375);
PAINT AQUA (-1400 1375);
DISPLAY INVISIBLE (-1400 1375);
FORCEADD VCC_CORE..1
(-900 1475);
FORCEPROP 3 LASTPIN (-900 1425) SIG_NAME P1V8_MCP_CPU0\g
J 0
(-890 1435);
DISPLAY 0.659574 (-890 1435);
PAINT MONO (-890 1435);
DISPLAY INVISIBLE (-890 1435);
FORCEPROP 1 LAST HDL_POWER P1V8_MCP_CPU0
J 1
(-900 1525);
DISPLAY 0.617021 (-900 1525);
PAINT GREEN (-900 1525);
FORCEPROP 2 LAST CDS_LIB mstr_symbols
J 0
(-900 1475);
PAINT ORANGE (-900 1475);
DISPLAY INVISIBLE (-900 1475);
FORCEPROP 1 LAST PATH I143
J 0
(-850 1500);
DISPLAY 0.872340 (-850 1500);
PAINT AQUA (-850 1500);
DISPLAY INVISIBLE (-850 1500);
FORCEADD VCC_CORE..1
(-5450 2575);
FORCEPROP 3 LASTPIN (-5450 2525) SIG_NAME PVCCIOMCP_CPU0\g
J 0
(-5440 2535);
DISPLAY 0.659574 (-5440 2535);
PAINT MONO (-5440 2535);
DISPLAY INVISIBLE (-5440 2535);
FORCEPROP 1 LAST HDL_POWER PVCCIOMCP_CPU0
J 1
(-5450 2625);
DISPLAY 0.617021 (-5450 2625);
PAINT GREEN (-5450 2625);
FORCEPROP 0 LAST VOLTAGE +0.95
J 0
(-5450 2725);
DISPLAY 1.021277 (-5450 2725);
PAINT SKYBLUE (-5450 2725);
DISPLAY INVISIBLE (-5450 2725);
FORCEPROP 2 LAST CDS_LIB mstr_symbols
J 0
(-5450 2575);
PAINT ORANGE (-5450 2575);
DISPLAY INVISIBLE (-5450 2575);
FORCEPROP 1 LAST PATH I144
J 0
(-5400 2600);
DISPLAY 0.872340 (-5400 2600);
PAINT AQUA (-5400 2600);
DISPLAY INVISIBLE (-5400 2600);
FORCEADD OFFPAGE..2
(-5250 975);
FORCEPROP 2 LAST $XR0 201 
J 0
(-5061 975);
DISPLAY 0.638298 (-5061 975);
PAINT MONO (-5061 975);
FORCEPROP 2 LAST $XR1 211 
J 0
(-4941 975);
DISPLAY 0.638298 (-4941 975);
PAINT MONO (-4941 975);
FORCEPROP 2 LAST $XR2 21 
J 0
(-4821 975);
DISPLAY 0.638298 (-4821 975);
PAINT MONO (-4821 975);
FORCEPROP 2 LAST CDS_LIB mstr_standard
J 0
(-5250 975);
PAINT ORANGE (-5250 975);
DISPLAY INVISIBLE (-5250 975);
FORCEPROP 2 LAST ROOM P0V95_FPGA_CPU0_VR
J 0
(-5675 1050);
DISPLAY 1.361702 (-5675 1050);
PAINT ORANGE (-5675 1050);
DISPLAY INVISIBLE (-5675 1050);
FORCEPROP 1 LAST OFFPAGE TRUE
J 0
(-4925 850);
DISPLAY 1.170213 (-4925 850);
PAINT GREEN (-4925 850);
DISPLAY INVISIBLE (-4925 850);
FORCEPROP 1 LAST COMMENT_BODY TRUE
J 0
(-5295 880);
DISPLAY 1.170213 (-5295 880);
PAINT GREEN (-5295 880);
DISPLAY INVISIBLE (-5295 880);
FORCEPROP 2 LAST PATH I148
J 0
(-4625 1025);
DISPLAY 1.021277 (-4625 1025);
PAINT ORANGE (-4625 1025);
DISPLAY INVISIBLE (-4625 1025);
FORCEADD CAP_A..1
(-1450 1100);
FORCEPROP 1 LAST LOCATION C3T1
J 0
(-1400 1200);
DISPLAY 0.617021 (-1400 1200);
PAINT AQUA (-1400 1200);
FORCEPROP 1 LAST PART_NUMBER 602433-106
J 0
(-1400 950);
DISPLAY 0.617021 (-1400 950);
PAINT BLUE (-1400 950);
FORCEPROP 1 LAST VALUE 47UF
J 0
(-1400 1150);
DISPLAY 0.617021 (-1400 1150);
PAINT SKYBLUE (-1400 1150);
FORCEPROP 1 LAST TOLERANCE 20%
J 0
(-1400 1050);
DISPLAY 0.617021 (-1400 1050);
PAINT SKYBLUE (-1400 1050);
FORCEPROP 1 LAST PACK_TYPE 0603V
J 0
(-1400 900);
DISPLAY 0.617021 (-1400 900);
PAINT SKYBLUE (-1400 900);
FORCEPROP 1 LAST VOLTAGE 4V
J 0
(-1400 1100);
DISPLAY 0.617021 (-1400 1100);
PAINT SKYBLUE (-1400 1100);
FORCEPROP 1 LAST MATERIAL X5R
J 0
(-1400 1000);
DISPLAY 0.617021 (-1400 1000);
PAINT SKYBLUE (-1400 1000);
FORCEPROP 1 LASTPIN (-1450 1200) $PN 1
J 0
(-1440 1180);
DISPLAY 0.617021 (-1440 1180);
PAINT ORANGE (-1440 1180);
FORCEPROP 1 LASTPIN (-1450 1000) $PN 2
J 0
(-1440 980);
DISPLAY 0.617021 (-1440 980);
PAINT ORANGE (-1440 980);
FORCEPROP 2 LAST CDS_LOCATION C3T1
J 0
(-1400 1200);
DISPLAY 0.617021 (-1400 1200);
PAINT AQUA (-1400 1200);
DISPLAY INVISIBLE (-1400 1200);
FORCEPROP 2 LAST CDS_LIB dev_discrete
J 0
(-1450 1100);
PAINT ORANGE (-1450 1100);
DISPLAY INVISIBLE (-1450 1100);
FORCEPROP 2 LAST CDS_SEC 1
J 0
(-1400 1250);
PAINT ORANGE (-1400 1250);
DISPLAY INVISIBLE (-1400 1250);
FORCEPROP 2 LAST SEC_TYPE 0603V
J 0
(-1400 1300);
DISPLAY 1.021277 (-1400 1300);
PAINT ORANGE (-1400 1300);
DISPLAY INVISIBLE (-1400 1300);
FORCEPROP 2 LAST SEC 1
J 0
(-1400 1300);
PAINT MONO (-1400 1300);
DISPLAY INVISIBLE (-1400 1300);
FORCEPROP 1 LAST PATH I149
J 0
(-1400 1250);
DISPLAY 0.978723 (-1400 1250);
PAINT WHITE (-1400 1250);
DISPLAY INVISIBLE (-1400 1250);
FORCEADD CAP_A..1
(-1750 1075);
FORCEPROP 1 LAST LOCATION C3T2
J 0
(-1700 1175);
DISPLAY 0.617021 (-1700 1175);
PAINT AQUA (-1700 1175);
FORCEPROP 1 LAST PART_NUMBER 602433-106
J 0
(-1700 925);
DISPLAY 0.617021 (-1700 925);
PAINT BLUE (-1700 925);
FORCEPROP 1 LAST VALUE 47UF
J 0
(-1700 1125);
DISPLAY 0.617021 (-1700 1125);
PAINT SKYBLUE (-1700 1125);
FORCEPROP 1 LAST TOLERANCE 20%
J 0
(-1700 1025);
DISPLAY 0.617021 (-1700 1025);
PAINT SKYBLUE (-1700 1025);
FORCEPROP 1 LAST PACK_TYPE 0603V
J 0
(-1700 875);
DISPLAY 0.617021 (-1700 875);
PAINT SKYBLUE (-1700 875);
FORCEPROP 1 LAST VOLTAGE 4V
J 0
(-1700 1075);
DISPLAY 0.617021 (-1700 1075);
PAINT SKYBLUE (-1700 1075);
FORCEPROP 1 LAST MATERIAL X5R
J 0
(-1700 975);
DISPLAY 0.617021 (-1700 975);
PAINT SKYBLUE (-1700 975);
FORCEPROP 1 LASTPIN (-1750 1175) $PN 1
J 0
(-1740 1155);
DISPLAY 0.617021 (-1740 1155);
PAINT ORANGE (-1740 1155);
FORCEPROP 1 LASTPIN (-1750 975) $PN 2
J 0
(-1740 955);
DISPLAY 0.617021 (-1740 955);
PAINT ORANGE (-1740 955);
FORCEPROP 2 LAST CDS_LOCATION C3T2
J 0
(-1700 1175);
DISPLAY 0.617021 (-1700 1175);
PAINT AQUA (-1700 1175);
DISPLAY INVISIBLE (-1700 1175);
FORCEPROP 2 LAST CDS_LIB dev_discrete
J 0
(-1750 1075);
PAINT ORANGE (-1750 1075);
DISPLAY INVISIBLE (-1750 1075);
FORCEPROP 2 LAST CDS_SEC 1
J 0
(-1700 1225);
PAINT ORANGE (-1700 1225);
DISPLAY INVISIBLE (-1700 1225);
FORCEPROP 2 LAST SEC_TYPE 0603V
J 0
(-1700 1275);
DISPLAY 1.021277 (-1700 1275);
PAINT ORANGE (-1700 1275);
DISPLAY INVISIBLE (-1700 1275);
FORCEPROP 2 LAST SEC 1
J 0
(-1700 1275);
PAINT MONO (-1700 1275);
DISPLAY INVISIBLE (-1700 1275);
FORCEPROP 1 LAST PATH I150
J 0
(-1700 1225);
DISPLAY 0.978723 (-1700 1225);
PAINT WHITE (-1700 1225);
DISPLAY INVISIBLE (-1700 1225);
FORCEADD GND..1
(-900 775);
FORCEPROP 3 LASTPIN (-900 825) SIG_NAME GND\g
J 0
(-890 835);
DISPLAY 0.659574 (-890 835);
PAINT MONO (-890 835);
DISPLAY INVISIBLE (-890 835);
FORCEPROP 1 LAST VOLTAGE 0
J 0
(-900 775);
DISPLAY 1.340426 (-900 775);
PAINT SKYBLUE (-900 775);
DISPLAY INVISIBLE (-900 775);
FORCEPROP 1 LAST SIZE 1B
J 0
(-825 725);
DISPLAY 1.191489 (-825 725);
PAINT GREEN (-825 725);
DISPLAY INVISIBLE (-825 725);
FORCEPROP 2 LAST CDS_LIB mstr_symbols
J 0
(-900 775);
PAINT ORANGE (-900 775);
DISPLAY INVISIBLE (-900 775);
FORCEPROP 1 LAST BODY_TYPE PLUMBING
J 0
(-945 732);
DISPLAY 0.340426 (-945 732);
PAINT GREEN (-945 732);
DISPLAY INVISIBLE (-945 732);
FORCEPROP 1 LAST PATH I151
J 0
(-825 775);
DISPLAY 0.872340 (-825 775);
PAINT AQUA (-825 775);
DISPLAY INVISIBLE (-825 775);
FORCEPROP 1 LAST HDL_POWER GND
J 0
(-900 925);
DISPLAY 1.191489 (-900 925);
PAINT GREEN (-900 925);
DISPLAY INVISIBLE (-900 925);
FORCEADD PVCCIO_CPU0..1
(-7425 3900);
FORCEPROP 3 LASTPIN (-7425 3850) SIG_NAME PVCCIO_CPU0\g
J 0
(-7415 3860);
DISPLAY 0.659574 (-7415 3860);
PAINT MONO (-7415 3860);
DISPLAY INVISIBLE (-7415 3860);
FORCEPROP 1 LAST VOLTAGE 1.1V
J 0
(-7470 3857);
DISPLAY 0.340426 (-7470 3857);
PAINT SKYBLUE (-7470 3857);
DISPLAY INVISIBLE (-7470 3857);
FORCEPROP 2 LAST CDS_LIB mstr_symbols
J 0
(-7425 3900);
PAINT ORANGE (-7425 3900);
DISPLAY INVISIBLE (-7425 3900);
FORCEPROP 1 LAST BODY_TYPE PLUMBING
J 0
(-7470 3857);
DISPLAY 0.340426 (-7470 3857);
PAINT GREEN (-7470 3857);
DISPLAY INVISIBLE (-7470 3857);
FORCEPROP 1 LAST PATH I154
J 0
(-7375 3925);
DISPLAY 0.872340 (-7375 3925);
PAINT AQUA (-7375 3925);
DISPLAY INVISIBLE (-7375 3925);
FORCEPROP 1 LAST HDL_POWER PVCCIO_CPU0
J 1
(-7425 3950);
DISPLAY 0.872340 (-7425 3950);
PAINT GREEN (-7425 3950);
DISPLAY INVISIBLE (-7425 3950);
FORCEADD RES..2
(-7825 100);
FORCEPROP 1 LAST LOCATION R7C24
J 0
(-7780 225);
DISPLAY 0.617021 (-7780 225);
PAINT AQUA (-7780 225);
FORCEPROP 1 LAST PART_NUMBER G21796-082
J 0
(-7785 -25);
DISPLAY 0.617021 (-7785 -25);
PAINT BLUE (-7785 -25);
FORCEPROP 1 LAST VALUE 4.02K
J 0
(-7780 175);
DISPLAY 0.617021 (-7780 175);
PAINT SKYBLUE (-7780 175);
FORCEPROP 1 LAST TOLERANCE 1%
J 0
(-7780 125);
DISPLAY 0.617021 (-7780 125);
PAINT SKYBLUE (-7780 125);
FORCEPROP 1 LAST PACK_TYPE 0402
J 0
(-7785 -75);
DISPLAY 0.617021 (-7785 -75);
PAINT SKYBLUE (-7785 -75);
FORCEPROP 1 LAST MATERIAL CHIP
J 0
(-7785 25);
DISPLAY 0.617021 (-7785 25);
PAINT SKYBLUE (-7785 25);
FORCEPROP 1 LAST WATTAGE 1/16W
J 0
(-7785 75);
DISPLAY 0.617021 (-7785 75);
PAINT SKYBLUE (-7785 75);
FORCEPROP 1 LASTPIN (-7825 0) $PN 2
J 0
(-7820 10);
DISPLAY 0.617021 (-7820 10);
PAINT ORANGE (-7820 10);
FORCEPROP 1 LASTPIN (-7825 200) $PN 1
J 0
(-7820 162);
DISPLAY 0.617021 (-7820 162);
PAINT ORANGE (-7820 162);
FORCEPROP 2 LAST SEC_TYPE 0402
J 0
(-7775 325);
DISPLAY 1.021277 (-7775 325);
PAINT ORANGE (-7775 325);
DISPLAY INVISIBLE (-7775 325);
FORCEPROP 2 LAST CDS_LIB mstr_discrete
J 0
(-7825 100);
PAINT ORANGE (-7825 100);
DISPLAY INVISIBLE (-7825 100);
FORCEPROP 2 LAST SEC 1
J 0
(-7775 325);
PAINT MONO (-7775 325);
DISPLAY INVISIBLE (-7775 325);
FORCEPROP 1 LAST PATH I155
J 0
(-7775 275);
DISPLAY 0.978723 (-7775 275);
PAINT WHITE (-7775 275);
DISPLAY INVISIBLE (-7775 275);
FORCEPROP 0 LAST ROOM PVCCIN_CPU1_VR
J 0
(-7775 325);
DISPLAY 1.021277 (-7775 325);
PAINT ORANGE (-7775 325);
DISPLAY INVISIBLE (-7775 325);
FORCEADD RES..2
(-8175 125);
FORCEPROP 1 LAST LOCATION R3N29
J 0
(-8130 250);
DISPLAY 0.617021 (-8130 250);
PAINT AQUA (-8130 250);
FORCEPROP 1 LAST PART_NUMBER G21796-317
J 0
(-8135 0);
DISPLAY 0.617021 (-8135 0);
PAINT BLUE (-8135 0);
FORCEPROP 1 LAST VALUE 16K
J 0
(-8130 200);
DISPLAY 0.617021 (-8130 200);
PAINT SKYBLUE (-8130 200);
FORCEPROP 1 LAST TOLERANCE 1.0%
J 0
(-8130 150);
DISPLAY 0.617021 (-8130 150);
PAINT SKYBLUE (-8130 150);
FORCEPROP 1 LAST PACK_TYPE 0402
J 0
(-8135 -50);
DISPLAY 0.617021 (-8135 -50);
PAINT SKYBLUE (-8135 -50);
FORCEPROP 1 LAST MATERIAL CHIP
J 0
(-8135 50);
DISPLAY 0.617021 (-8135 50);
PAINT SKYBLUE (-8135 50);
FORCEPROP 1 LAST WATTAGE 1/16W
J 0
(-8135 100);
DISPLAY 0.617021 (-8135 100);
PAINT SKYBLUE (-8135 100);
FORCEPROP 1 LASTPIN (-8175 25) $PN 2
J 0
(-8170 35);
DISPLAY 0.617021 (-8170 35);
PAINT ORANGE (-8170 35);
FORCEPROP 1 LASTPIN (-8175 225) $PN 1
J 0
(-8170 187);
DISPLAY 0.617021 (-8170 187);
PAINT ORANGE (-8170 187);
FORCEPROP 2 LAST SEC_TYPE 0402
J 0
(-8125 350);
DISPLAY 1.021277 (-8125 350);
PAINT ORANGE (-8125 350);
DISPLAY INVISIBLE (-8125 350);
FORCEPROP 2 LAST CDS_LIB mstr_discrete
J 0
(-8175 125);
PAINT ORANGE (-8175 125);
DISPLAY INVISIBLE (-8175 125);
FORCEPROP 2 LAST SEC 1
J 0
(-8125 350);
PAINT MONO (-8125 350);
DISPLAY INVISIBLE (-8125 350);
FORCEPROP 1 LAST PATH I156
J 0
(-8125 300);
DISPLAY 0.978723 (-8125 300);
PAINT WHITE (-8125 300);
DISPLAY INVISIBLE (-8125 300);
FORCEPROP 0 LAST ROOM VDDQ_ABC_PWR_VR
J 0
(-8125 350);
DISPLAY 1.021277 (-8125 350);
PAINT ORANGE (-8125 350);
DISPLAY INVISIBLE (-8125 350);
FORCEADD GND..1
(-7975 -225);
FORCEPROP 3 LASTPIN (-7975 -175) SIG_NAME GND\g
J 0
(-7965 -165);
DISPLAY 0.659574 (-7965 -165);
PAINT MONO (-7965 -165);
DISPLAY INVISIBLE (-7965 -165);
FORCEPROP 1 LAST VOLTAGE 0.0V
J 0
(-8020 -268);
DISPLAY 0.340426 (-8020 -268);
PAINT SKYBLUE (-8020 -268);
DISPLAY INVISIBLE (-8020 -268);
FORCEPROP 2 LAST CDS_LIB mstr_symbols
J 0
(-7975 -225);
PAINT ORANGE (-7975 -225);
DISPLAY INVISIBLE (-7975 -225);
FORCEPROP 1 LAST SIZE 1B
J 0
(-7900 -275);
DISPLAY 1.404255 (-7900 -275);
PAINT AQUA (-7900 -275);
DISPLAY INVISIBLE (-7900 -275);
FORCEPROP 1 LAST BODY_TYPE PLUMBING
J 0
(-8020 -268);
DISPLAY 0.340426 (-8020 -268);
PAINT GREEN (-8020 -268);
DISPLAY INVISIBLE (-8020 -268);
FORCEPROP 1 LAST PATH I157
J 0
(-7900 -225);
DISPLAY 0.872340 (-7900 -225);
PAINT AQUA (-7900 -225);
DISPLAY INVISIBLE (-7900 -225);
FORCEPROP 1 LAST HDL_POWER GND
J 0
(-7975 -75);
PAINT GREEN (-7975 -75);
DISPLAY INVISIBLE (-7975 -75);
FORCEADD OFFPAGE..2
(-5300 475);
FORCEPROP 2 LAST $XR0 190 
J 0
(-5111 475);
DISPLAY 0.638298 (-5111 475);
PAINT MONO (-5111 475);
FORCEPROP 2 LAST CDS_LIB mstr_standard
J 0
(-5300 475);
PAINT ORANGE (-5300 475);
DISPLAY INVISIBLE (-5300 475);
FORCEPROP 2 LAST ROOM P0V95_FPGA_CPU0_VR
J 0
(-5725 550);
DISPLAY 1.361702 (-5725 550);
PAINT ORANGE (-5725 550);
DISPLAY INVISIBLE (-5725 550);
FORCEPROP 1 LAST OFFPAGE TRUE
J 0
(-4975 350);
DISPLAY 1.170213 (-4975 350);
PAINT GREEN (-4975 350);
DISPLAY INVISIBLE (-4975 350);
FORCEPROP 1 LAST COMMENT_BODY TRUE
J 0
(-5345 380);
DISPLAY 1.170213 (-5345 380);
PAINT GREEN (-5345 380);
DISPLAY INVISIBLE (-5345 380);
FORCEPROP 2 LAST PATH I158
J 0
(-5100 525);
DISPLAY 1.021277 (-5100 525);
PAINT ORANGE (-5100 525);
DISPLAY INVISIBLE (-5100 525);
FORCEADD OFFPAGE..4
(-5300 525);
FORCEPROP 2 LAST $XR0 190 
J 0
(-5084 525);
DISPLAY 0.638298 (-5084 525);
PAINT MONO (-5084 525);
FORCEPROP 2 LAST CDS_LIB mstr_standard
J 0
(-5300 525);
PAINT ORANGE (-5300 525);
DISPLAY INVISIBLE (-5300 525);
FORCEPROP 2 LAST ROOM P0V95_FPGA_CPU0_VR
J 0
(-5850 600);
DISPLAY 1.361702 (-5850 600);
PAINT ORANGE (-5850 600);
DISPLAY INVISIBLE (-5850 600);
FORCEPROP 1 LAST OFFPAGE TRUE
J 0
(-4975 400);
DISPLAY 0.872340 (-4975 400);
PAINT GREEN (-4975 400);
DISPLAY INVISIBLE (-4975 400);
FORCEPROP 1 LAST COMMENT_BODY TRUE
J 0
(-5325 425);
DISPLAY 0.872340 (-5325 425);
PAINT GREEN (-5325 425);
DISPLAY INVISIBLE (-5325 425);
FORCEPROP 2 LAST PATH I159
J 0
(-5100 575);
DISPLAY 1.021277 (-5100 575);
PAINT ORANGE (-5100 575);
DISPLAY INVISIBLE (-5100 575);
FORCEADD CAP_A..1
R 2
(-900 1075);
FORCEPROP 1 LAST LOCATION C4T1
J 2
(-950 1175);
DISPLAY 0.617021 (-950 1175);
PAINT AQUA (-950 1175);
FORCEPROP 1 LAST PART_NUMBER D97712-004
J 2
(-950 925);
DISPLAY 0.617021 (-950 925);
PAINT BLUE (-950 925);
FORCEPROP 1 LAST VALUE 1.0UF
J 2
(-950 1125);
DISPLAY 0.617021 (-950 1125);
PAINT SKYBLUE (-950 1125);
FORCEPROP 1 LAST TOLERANCE 10%
J 2
(-950 1025);
DISPLAY 0.617021 (-950 1025);
PAINT SKYBLUE (-950 1025);
FORCEPROP 1 LAST PACK_TYPE 0402V
J 2
(-950 875);
DISPLAY 0.617021 (-950 875);
PAINT SKYBLUE (-950 875);
FORCEPROP 1 LAST VOLTAGE 6.3V
J 2
(-950 1075);
DISPLAY 0.617021 (-950 1075);
PAINT SKYBLUE (-950 1075);
FORCEPROP 1 LAST MATERIAL X6S
J 2
(-950 975);
DISPLAY 0.617021 (-950 975);
PAINT SKYBLUE (-950 975);
FORCEPROP 1 LASTPIN (-900 1175) $PN 1
J 2
(-910 1155);
DISPLAY 0.617021 (-910 1155);
PAINT ORANGE (-910 1155);
FORCEPROP 1 LASTPIN (-900 975) $PN 2
J 2
(-910 955);
DISPLAY 0.617021 (-910 955);
PAINT ORANGE (-910 955);
FORCEPROP 2 LAST CDS_LOCATION C4T1
J 2
(-950 1175);
DISPLAY 0.617021 (-950 1175);
PAINT AQUA (-950 1175);
DISPLAY INVISIBLE (-950 1175);
FORCEPROP 2 LAST CDS_LIB dev_discrete
J 0
(-900 1075);
PAINT ORANGE (-900 1075);
DISPLAY INVISIBLE (-900 1075);
FORCEPROP 2 LAST CDS_SEC 1
J 0
(-950 1225);
PAINT ORANGE (-950 1225);
DISPLAY INVISIBLE (-950 1225);
FORCEPROP 2 LAST SEC_TYPE 0402V
J 0
(-950 1275);
DISPLAY 1.021277 (-950 1275);
PAINT ORANGE (-950 1275);
DISPLAY INVISIBLE (-950 1275);
FORCEPROP 2 LAST SEC 1
J 0
(-950 1275);
DISPLAY 0.680851 (-950 1275);
PAINT MONO (-950 1275);
DISPLAY INVISIBLE (-950 1275);
FORCEPROP 1 LAST PATH I16
J 2
(-950 1225);
DISPLAY 0.978723 (-950 1225);
PAINT WHITE (-950 1225);
DISPLAY INVISIBLE (-950 1225);
FORCEPROP 2 LAST ROOM P1V8_MCP_CPU0
J 2
(-950 1225);
DISPLAY 1.659574 (-950 1225);
PAINT WHITE (-950 1225);
DISPLAY INVISIBLE (-950 1225);
FORCEADD OFFPAGE..3
(-5325 375);
FORCEPROP 2 LAST $XR0 21 
J 0
(-5111 375);
DISPLAY 0.638298 (-5111 375);
PAINT MONO (-5111 375);
FORCEPROP 2 LAST $XR1 215 
J 0
(-5021 375);
DISPLAY 0.638298 (-5021 375);
PAINT MONO (-5021 375);
FORCEPROP 2 LAST $XR2 218 
J 0
(-4901 375);
DISPLAY 0.638298 (-4901 375);
PAINT MONO (-4901 375);
FORCEPROP 2 LAST ROOM P0V95_FPGA_CPU0_VR
J 0
(-5725 450);
DISPLAY 1.361702 (-5725 450);
PAINT ORANGE (-5725 450);
DISPLAY INVISIBLE (-5725 450);
FORCEPROP 2 LAST CDS_LIB mstr_standard
J 0
(-5325 375);
PAINT ORANGE (-5325 375);
DISPLAY INVISIBLE (-5325 375);
FORCEPROP 1 LAST OFFPAGE TRUE
J 0
(-5000 250);
DISPLAY 1.170213 (-5000 250);
PAINT GREEN (-5000 250);
DISPLAY INVISIBLE (-5000 250);
FORCEPROP 1 LAST COMMENT_BODY TRUE
J 0
(-5375 275);
DISPLAY 1.170213 (-5375 275);
PAINT GREEN (-5375 275);
DISPLAY INVISIBLE (-5375 275);
FORCEPROP 2 LAST PATH I160
J 0
(-4900 425);
DISPLAY 1.021277 (-4900 425);
PAINT ORANGE (-4900 425);
DISPLAY INVISIBLE (-4900 425);
FORCEADD OFFPAGE..4
(-5325 425);
FORCEPROP 2 LAST $XR0 21 
J 0
(-5109 425);
DISPLAY 0.638298 (-5109 425);
PAINT MONO (-5109 425);
FORCEPROP 2 LAST $XR1 215 
J 0
(-5019 425);
DISPLAY 0.638298 (-5019 425);
PAINT MONO (-5019 425);
FORCEPROP 2 LAST $XR2 218 
J 0
(-4899 425);
DISPLAY 0.638298 (-4899 425);
PAINT MONO (-4899 425);
FORCEPROP 2 LAST ROOM P0V95_FPGA_CPU0_VR
J 0
(-5875 500);
DISPLAY 1.361702 (-5875 500);
PAINT ORANGE (-5875 500);
DISPLAY INVISIBLE (-5875 500);
FORCEPROP 2 LAST CDS_LIB mstr_standard
J 0
(-5325 425);
PAINT MONO (-5325 425);
DISPLAY INVISIBLE (-5325 425);
FORCEPROP 1 LAST OFFPAGE TRUE
J 0
(-5000 300);
DISPLAY 0.872340 (-5000 300);
PAINT GREEN (-5000 300);
DISPLAY INVISIBLE (-5000 300);
FORCEPROP 1 LAST COMMENT_BODY TRUE
J 0
(-5350 325);
DISPLAY 0.872340 (-5350 325);
PAINT GREEN (-5350 325);
DISPLAY INVISIBLE (-5350 325);
FORCEPROP 2 LAST PATH I161
J 0
(-4875 475);
DISPLAY 1.021277 (-4875 475);
PAINT ORANGE (-4875 475);
DISPLAY INVISIBLE (-4875 475);
FORCEADD OFFPAGE..3
(-5275 575);
FORCEPROP 2 LAST $XR0 21 
J 0
(-5061 575);
DISPLAY 0.638298 (-5061 575);
PAINT MONO (-5061 575);
FORCEPROP 2 LAST $XR1 201 
J 0
(-4971 575);
DISPLAY 0.638298 (-4971 575);
PAINT MONO (-4971 575);
FORCEPROP 2 LAST $XR2 211 
J 0
(-4851 575);
DISPLAY 0.638298 (-4851 575);
PAINT MONO (-4851 575);
FORCEPROP 2 LAST ROOM P0V95_FPGA_CPU0_VR
J 0
(-5675 650);
DISPLAY 1.361702 (-5675 650);
PAINT ORANGE (-5675 650);
DISPLAY INVISIBLE (-5675 650);
FORCEPROP 2 LAST CDS_LIB mstr_standard
J 0
(-5275 575);
PAINT ORANGE (-5275 575);
DISPLAY INVISIBLE (-5275 575);
FORCEPROP 1 LAST OFFPAGE TRUE
J 0
(-4950 450);
DISPLAY 1.170213 (-4950 450);
PAINT GREEN (-4950 450);
DISPLAY INVISIBLE (-4950 450);
FORCEPROP 1 LAST COMMENT_BODY TRUE
J 0
(-5325 475);
DISPLAY 1.170213 (-5325 475);
PAINT GREEN (-5325 475);
DISPLAY INVISIBLE (-5325 475);
FORCEPROP 2 LAST PATH I162
J 0
(-4850 625);
DISPLAY 1.021277 (-4850 625);
PAINT ORANGE (-4850 625);
DISPLAY INVISIBLE (-4850 625);
FORCEADD OFFPAGE..2
(-5250 925);
FORCEPROP 2 LAST $XR0 215 
J 0
(-5061 925);
DISPLAY 0.638298 (-5061 925);
PAINT MONO (-5061 925);
FORCEPROP 2 LAST $XR1 218 
J 0
(-4941 925);
DISPLAY 0.638298 (-4941 925);
PAINT MONO (-4941 925);
FORCEPROP 2 LAST $XR2 21 
J 0
(-4821 925);
DISPLAY 0.638298 (-4821 925);
PAINT MONO (-4821 925);
FORCEPROP 2 LAST ROOM P0V95_FPGA_CPU0_VR
J 0
(-5675 1000);
DISPLAY 1.361702 (-5675 1000);
PAINT ORANGE (-5675 1000);
DISPLAY INVISIBLE (-5675 1000);
FORCEPROP 2 LAST CDS_LIB mstr_standard
J 0
(-5250 925);
PAINT ORANGE (-5250 925);
DISPLAY INVISIBLE (-5250 925);
FORCEPROP 1 LAST OFFPAGE TRUE
J 0
(-4925 800);
DISPLAY 1.170213 (-4925 800);
PAINT GREEN (-4925 800);
DISPLAY INVISIBLE (-4925 800);
FORCEPROP 1 LAST COMMENT_BODY TRUE
J 0
(-5295 830);
DISPLAY 1.170213 (-5295 830);
PAINT GREEN (-5295 830);
DISPLAY INVISIBLE (-5295 830);
FORCEPROP 2 LAST PATH I163
J 0
(-4800 975);
DISPLAY 1.021277 (-4800 975);
PAINT ORANGE (-4800 975);
DISPLAY INVISIBLE (-4800 975);
FORCEADD OFFPAGE..1
(-5000 3475);
FORCEPROP 2 LAST $XR0 22 
J 0
(-5221 3475);
DISPLAY 0.638298 (-5221 3475);
PAINT MONO (-5221 3475);
FORCEPROP 2 LAST CDS_LIB mstr_standard
J 0
(-5000 3475);
PAINT ORANGE (-5000 3475);
DISPLAY INVISIBLE (-5000 3475);
FORCEPROP 1 LAST OFFPAGE TRUE
J 0
(-4675 3350);
DISPLAY 1.170213 (-4675 3350);
PAINT GREEN (-4675 3350);
DISPLAY INVISIBLE (-4675 3350);
FORCEPROP 1 LAST COMMENT_BODY TRUE
J 0
(-4875 3375);
DISPLAY 1.170213 (-4875 3375);
PAINT GREEN (-4875 3375);
DISPLAY INVISIBLE (-4875 3375);
FORCEPROP 2 LAST PATH I164
J 0
(-4950 3550);
DISPLAY 1.021277 (-4950 3550);
PAINT ORANGE (-4950 3550);
DISPLAY INVISIBLE (-4950 3550);
FORCEADD OFFPAGE..1
(-5000 3550);
FORCEPROP 2 LAST $XR0 22 
J 0
(-5221 3550);
DISPLAY 0.638298 (-5221 3550);
PAINT MONO (-5221 3550);
FORCEPROP 2 LAST CDS_LIB mstr_standard
J 0
(-5000 3550);
PAINT ORANGE (-5000 3550);
DISPLAY INVISIBLE (-5000 3550);
FORCEPROP 1 LAST OFFPAGE TRUE
J 0
(-4675 3425);
DISPLAY 1.170213 (-4675 3425);
PAINT GREEN (-4675 3425);
DISPLAY INVISIBLE (-4675 3425);
FORCEPROP 1 LAST COMMENT_BODY TRUE
J 0
(-4875 3450);
DISPLAY 1.170213 (-4875 3450);
PAINT GREEN (-4875 3450);
DISPLAY INVISIBLE (-4875 3450);
FORCEPROP 2 LAST PATH I165
J 0
(-4950 3625);
DISPLAY 1.021277 (-4950 3625);
PAINT ORANGE (-4950 3625);
DISPLAY INVISIBLE (-4950 3625);
FORCEADD OFFPAGE..5
(-4850 2200);
FORCEPROP 2 LAST $XR0 104 
J 0
(-5105 2200);
DISPLAY 0.638298 (-5105 2200);
PAINT MONO (-5105 2200);
FORCEPROP 2 LAST CDS_LIB mstr_standard
J 0
(-4850 2200);
PAINT ORANGE (-4850 2200);
DISPLAY INVISIBLE (-4850 2200);
FORCEPROP 2 LAST ROOM PVSA_CPU0_VSENSE_VR
J 0
(-5250 2275);
PAINT ORANGE (-5250 2275);
DISPLAY INVISIBLE (-5250 2275);
FORCEPROP 2 LAST BOM_COST PROC_VRD_VCCIN_CPU0
J 0
(-4525 2250);
PAINT MONO (-4525 2250);
DISPLAY INVISIBLE (-4525 2250);
FORCEPROP 1 LAST OFFPAGE TRUE
J 0
(-4525 2075);
DISPLAY 0.872340 (-4525 2075);
PAINT GREEN (-4525 2075);
DISPLAY INVISIBLE (-4525 2075);
FORCEPROP 1 LAST COMMENT_BODY TRUE
J 0
(-4750 2125);
DISPLAY 0.872340 (-4750 2125);
PAINT GREEN (-4750 2125);
DISPLAY INVISIBLE (-4750 2125);
FORCEPROP 2 LAST PATH I166
J 0
(-5100 2250);
DISPLAY 1.021277 (-5100 2250);
PAINT ORANGE (-5100 2250);
DISPLAY INVISIBLE (-5100 2250);
FORCEADD OFFPAGE..5
(-4875 2150);
FORCEPROP 2 LAST $XR0 104 
J 0
(-5130 2150);
DISPLAY 0.638298 (-5130 2150);
PAINT MONO (-5130 2150);
FORCEPROP 2 LAST CDS_LIB mstr_standard
J 0
(-4875 2150);
PAINT ORANGE (-4875 2150);
DISPLAY INVISIBLE (-4875 2150);
FORCEPROP 2 LAST ROOM PVSA_CPU0_VSENSE_VR
J 0
(-5275 2225);
PAINT ORANGE (-5275 2225);
DISPLAY INVISIBLE (-5275 2225);
FORCEPROP 2 LAST BOM_COST PROC_VRD_VCCIN_CPU0
J 0
(-4550 2200);
PAINT MONO (-4550 2200);
DISPLAY INVISIBLE (-4550 2200);
FORCEPROP 1 LAST OFFPAGE TRUE
J 0
(-4550 2025);
DISPLAY 0.872340 (-4550 2025);
PAINT GREEN (-4550 2025);
DISPLAY INVISIBLE (-4550 2025);
FORCEPROP 1 LAST COMMENT_BODY TRUE
J 0
(-4775 2075);
DISPLAY 0.872340 (-4775 2075);
PAINT GREEN (-4775 2075);
DISPLAY INVISIBLE (-4775 2075);
FORCEPROP 2 LAST PATH I167
J 0
(-5125 2200);
DISPLAY 1.021277 (-5125 2200);
PAINT ORANGE (-5125 2200);
DISPLAY INVISIBLE (-5125 2200);
FORCEADD P3V3..1
(-7525 3800);
FORCEPROP 3 LASTPIN (-7525 3750) SIG_NAME P3V3\g
J 0
(-7515 3760);
DISPLAY 0.659574 (-7515 3760);
PAINT MONO (-7515 3760);
DISPLAY INVISIBLE (-7515 3760);
FORCEPROP 1 LAST VOLTAGE +3.3V
J 0
(-7425 3950);
DISPLAY 1.021277 (-7425 3950);
PAINT SKYBLUE (-7425 3950);
DISPLAY INVISIBLE (-7425 3950);
FORCEPROP 2 LAST CDS_LIB mstr_symbols
J 0
(-7525 3800);
PAINT ORANGE (-7525 3800);
DISPLAY INVISIBLE (-7525 3800);
FORCEPROP 1 LAST SIZE 1B
J 0
(-7480 3822);
DISPLAY 0.340426 (-7480 3822);
PAINT GREEN (-7480 3822);
DISPLAY INVISIBLE (-7480 3822);
FORCEPROP 1 LAST BODY_TYPE PLUMBING
J 0
(-7570 3757);
DISPLAY 0.340426 (-7570 3757);
PAINT GREEN (-7570 3757);
DISPLAY INVISIBLE (-7570 3757);
FORCEPROP 1 LAST PATH I170
J 0
(-7480 3802);
DISPLAY 0.340426 (-7480 3802);
PAINT GREEN (-7480 3802);
DISPLAY INVISIBLE (-7480 3802);
FORCEPROP 1 LAST HDL_POWER P3V3
J 0
(-7850 3675);
DISPLAY 0.872340 (-7850 3675);
PAINT ORANGE (-7850 3675);
DISPLAY INVISIBLE (-7850 3675);
FORCEADD OFFPAGE..1
(-8125 3575);
FORCEPROP 2 LAST $XR0 104 
J 0
(-8377 3575);
DISPLAY 0.638298 (-8377 3575);
PAINT MONO (-8377 3575);
FORCEPROP 2 LAST CDS_LIB mstr_standard
J 0
(-8125 3575);
PAINT ORANGE (-8125 3575);
DISPLAY INVISIBLE (-8125 3575);
FORCEPROP 1 LAST OFFPAGE TRUE
J 0
(-7800 3450);
DISPLAY 1.170213 (-7800 3450);
PAINT GREEN (-7800 3450);
DISPLAY INVISIBLE (-7800 3450);
FORCEPROP 1 LAST COMMENT_BODY TRUE
J 0
(-8000 3475);
DISPLAY 1.170213 (-8000 3475);
PAINT GREEN (-8000 3475);
DISPLAY INVISIBLE (-8000 3475);
FORCEPROP 2 LAST PATH I171
J 0
(-8075 3650);
DISPLAY 1.021277 (-8075 3650);
PAINT ORANGE (-8075 3650);
DISPLAY INVISIBLE (-8075 3650);
FORCEADD GND..1
(-1450 750);
FORCEPROP 3 LASTPIN (-1450 800) SIG_NAME GND\g
J 0
(-1440 810);
DISPLAY 0.659574 (-1440 810);
PAINT MONO (-1440 810);
DISPLAY INVISIBLE (-1440 810);
FORCEPROP 1 LAST VOLTAGE 0
J 0
(-1450 750);
DISPLAY 1.340426 (-1450 750);
PAINT SKYBLUE (-1450 750);
DISPLAY INVISIBLE (-1450 750);
FORCEPROP 1 LAST SIZE 1B
J 0
(-1375 700);
DISPLAY 1.191489 (-1375 700);
PAINT GREEN (-1375 700);
DISPLAY INVISIBLE (-1375 700);
FORCEPROP 2 LAST CDS_LIB mstr_symbols
J 0
(-1450 750);
PAINT ORANGE (-1450 750);
DISPLAY INVISIBLE (-1450 750);
FORCEPROP 1 LAST BODY_TYPE PLUMBING
J 0
(-1495 707);
DISPLAY 0.340426 (-1495 707);
PAINT GREEN (-1495 707);
DISPLAY INVISIBLE (-1495 707);
FORCEPROP 1 LAST PATH I28
J 0
(-1375 750);
DISPLAY 0.872340 (-1375 750);
PAINT AQUA (-1375 750);
DISPLAY INVISIBLE (-1375 750);
FORCEPROP 1 LAST HDL_POWER GND
J 0
(-1450 900);
DISPLAY 1.191489 (-1450 900);
PAINT GREEN (-1450 900);
DISPLAY INVISIBLE (-1450 900);
FORCEADD CAPP..1
(-850 2275);
FORCEPROP 1 LAST LOCATION C4R1
J 0
(-800 2375);
DISPLAY 0.617021 (-800 2375);
PAINT AQUA (-800 2375);
FORCEPROP 1 LAST PART_NUMBER 699013-049
J 0
(-800 2075);
DISPLAY 0.617021 (-800 2075);
PAINT BLUE (-800 2075);
FORCEPROP 1 LAST VALUE 470UF
J 0
(-800 2325);
DISPLAY 0.617021 (-800 2325);
PAINT SKYBLUE (-800 2325);
FORCEPROP 1 LAST TOLERANCE 20%
J 0
(-800 2275);
DISPLAY 0.617021 (-800 2275);
PAINT SKYBLUE (-800 2275);
FORCEPROP 1 LAST PACK_TYPE 3018
J 0
(-800 2125);
DISPLAY 0.617021 (-800 2125);
PAINT SKYBLUE (-800 2125);
FORCEPROP 1 LAST MATERIAL ALUM
J 0
(-800 2175);
DISPLAY 0.617021 (-800 2175);
PAINT SKYBLUE (-800 2175);
FORCEPROP 1 LASTPIN (-850 2175) $PN 2
J 0
(-840 2160);
DISPLAY 0.617021 (-840 2160);
PAINT WHITE (-840 2160);
FORCEPROP 1 LASTPIN (-850 2375) $PN 1
J 0
(-840 2360);
DISPLAY 0.617021 (-840 2360);
PAINT WHITE (-840 2360);
FORCEPROP 1 LAST VOLTAGE 2.5V
J 0
(-800 2225);
DISPLAY 1.617021 (-800 2225);
PAINT SKYBLUE (-800 2225);
DISPLAY INVISIBLE (-800 2225);
FORCEPROP 2 LAST CDS_LIB mstr_discrete
J 0
(-850 2275);
DISPLAY 1.617021 (-850 2275);
PAINT ORANGE (-850 2275);
DISPLAY INVISIBLE (-850 2275);
FORCEPROP 2 LAST BOM_COST PVMCP_MCP_CPU0_VR
J 0
(-800 2425);
DISPLAY 1.617021 (-800 2425);
PAINT WHITE (-800 2425);
DISPLAY INVISIBLE (-800 2425);
FORCEPROP 2 LAST SEC_TYPE 3018
J 0
(-795 2495);
DISPLAY 1.659574 (-795 2495);
PAINT ORANGE (-795 2495);
DISPLAY INVISIBLE (-795 2495);
FORCEPROP 2 LAST SEC 1
J 0
(-795 2495);
DISPLAY 1.106383 (-795 2495);
PAINT MONO (-795 2495);
DISPLAY INVISIBLE (-795 2495);
FORCEPROP 2 LAST CDS_LOCATION C4R1
J 0
(-800 2375);
DISPLAY 0.617021 (-800 2375);
PAINT AQUA (-800 2375);
DISPLAY INVISIBLE (-800 2375);
FORCEPROP 1 LAST PATH I29
J 0
(-800 2425);
DISPLAY 0.978723 (-800 2425);
PAINT ORANGE (-800 2425);
DISPLAY INVISIBLE (-800 2425);
FORCEPROP 2 LAST ROOM PVMCP_MCP_CPU0_VR
J 0
(-800 2400);
DISPLAY 1.617021 (-800 2400);
PAINT WHITE (-800 2400);
DISPLAY INVISIBLE (-800 2400);
FORCEADD VCC_CORE..1
(-1275 2600);
FORCEPROP 3 LASTPIN (-1275 2550) SIG_NAME PVCCMCP_CPU0\g
J 0
(-1265 2560);
DISPLAY 0.659574 (-1265 2560);
PAINT MONO (-1265 2560);
DISPLAY INVISIBLE (-1265 2560);
FORCEPROP 1 LAST HDL_POWER PVCCMCP_CPU0
J 1
(-1275 2650);
DISPLAY 0.617021 (-1275 2650);
PAINT GREEN (-1275 2650);
FORCEPROP 2 LAST CDS_LIB mstr_symbols
J 0
(-1275 2600);
PAINT ORANGE (-1275 2600);
DISPLAY INVISIBLE (-1275 2600);
FORCEPROP 2 LAST BOM_COST PVMCP_FPGA_CPU0_VR
J 0
(-1275 2700);
DISPLAY 2.340426 (-1275 2700);
PAINT WHITE (-1275 2700);
DISPLAY INVISIBLE (-1275 2700);
FORCEPROP 1 LAST PATH I30
J 0
(-1225 2625);
DISPLAY 0.872340 (-1225 2625);
PAINT AQUA (-1225 2625);
DISPLAY INVISIBLE (-1225 2625);
FORCEPROP 2 LAST ROOM PVMCP_FPGA_CPU0_VR
J 0
(-1275 2700);
DISPLAY 3.127660 (-1275 2700);
PAINT WHITE (-1275 2700);
DISPLAY INVISIBLE (-1275 2700);
FORCEADD CAPP..1
(-1275 2275);
FORCEPROP 1 LAST LOCATION C3R4
J 0
(-1225 2375);
DISPLAY 0.617021 (-1225 2375);
PAINT AQUA (-1225 2375);
FORCEPROP 1 LAST PART_NUMBER 699013-049
J 0
(-1225 2075);
DISPLAY 0.617021 (-1225 2075);
PAINT BLUE (-1225 2075);
FORCEPROP 1 LAST VALUE 470UF
J 0
(-1225 2325);
DISPLAY 0.617021 (-1225 2325);
PAINT SKYBLUE (-1225 2325);
FORCEPROP 1 LAST TOLERANCE 20%
J 0
(-1225 2275);
DISPLAY 0.617021 (-1225 2275);
PAINT SKYBLUE (-1225 2275);
FORCEPROP 1 LAST PACK_TYPE 3018
J 0
(-1225 2125);
DISPLAY 0.617021 (-1225 2125);
PAINT SKYBLUE (-1225 2125);
FORCEPROP 1 LAST MATERIAL ALUM
J 0
(-1225 2175);
DISPLAY 0.617021 (-1225 2175);
PAINT SKYBLUE (-1225 2175);
FORCEPROP 1 LASTPIN (-1275 2175) $PN 2
J 0
(-1265 2160);
DISPLAY 0.617021 (-1265 2160);
PAINT WHITE (-1265 2160);
FORCEPROP 1 LASTPIN (-1275 2375) $PN 1
J 0
(-1265 2360);
DISPLAY 0.617021 (-1265 2360);
PAINT WHITE (-1265 2360);
FORCEPROP 1 LAST VOLTAGE 2.5V
J 0
(-1225 2225);
DISPLAY 1.617021 (-1225 2225);
PAINT SKYBLUE (-1225 2225);
DISPLAY INVISIBLE (-1225 2225);
FORCEPROP 2 LAST CDS_LIB mstr_discrete
J 0
(-1275 2275);
DISPLAY 1.617021 (-1275 2275);
PAINT ORANGE (-1275 2275);
DISPLAY INVISIBLE (-1275 2275);
FORCEPROP 2 LAST BOM_COST PVMCP_MCP_CPU0_VR
J 0
(-1225 2425);
DISPLAY 1.617021 (-1225 2425);
PAINT WHITE (-1225 2425);
DISPLAY INVISIBLE (-1225 2425);
FORCEPROP 2 LAST CDS_SEC 1
J 0
(-1225 2475);
DISPLAY 1.617021 (-1225 2475);
PAINT MONO (-1225 2475);
DISPLAY INVISIBLE (-1225 2475);
FORCEPROP 2 LAST $SEC 1
J 0
(-1225 2475);
DISPLAY 1.617021 (-1225 2475);
PAINT MONO (-1225 2475);
DISPLAY INVISIBLE (-1225 2475);
FORCEPROP 2 LAST CDS_LOCATION C3R4
J 0
(-1225 2375);
DISPLAY 0.617021 (-1225 2375);
PAINT AQUA (-1225 2375);
DISPLAY INVISIBLE (-1225 2375);
FORCEPROP 1 LAST PATH I31
J 0
(-1225 2425);
DISPLAY 0.978723 (-1225 2425);
PAINT ORANGE (-1225 2425);
DISPLAY INVISIBLE (-1225 2425);
FORCEPROP 2 LAST ROOM PVMCP_MCP_CPU0_VR
J 0
(-1225 2400);
DISPLAY 1.617021 (-1225 2400);
PAINT WHITE (-1225 2400);
DISPLAY INVISIBLE (-1225 2400);
FORCEADD GND..1
(-1275 1875);
FORCEPROP 3 LASTPIN (-1275 1925) SIG_NAME GND\g
J 0
(-1265 1935);
DISPLAY 0.659574 (-1265 1935);
PAINT MONO (-1265 1935);
DISPLAY INVISIBLE (-1265 1935);
FORCEPROP 1 LAST VOLTAGE 0.0V
J 0
(-1320 1832);
DISPLAY 0.340426 (-1320 1832);
PAINT SKYBLUE (-1320 1832);
DISPLAY INVISIBLE (-1320 1832);
FORCEPROP 2 LAST CDS_LIB mstr_symbols
J 0
(-1275 1875);
DISPLAY 1.617021 (-1275 1875);
PAINT ORANGE (-1275 1875);
DISPLAY INVISIBLE (-1275 1875);
FORCEPROP 1 LAST SIZE 1B
J 0
(-1200 1825);
DISPLAY 2.787234 (-1200 1825);
PAINT GREEN (-1200 1825);
DISPLAY INVISIBLE (-1200 1825);
FORCEPROP 2 LAST BOM_COST PVMCP_FPGA_CPU0_VR
J 0
(-1650 1950);
DISPLAY 2.340426 (-1650 1950);
PAINT WHITE (-1650 1950);
DISPLAY INVISIBLE (-1650 1950);
FORCEPROP 1 LAST BODY_TYPE PLUMBING
J 0
(-1320 1832);
DISPLAY 0.340426 (-1320 1832);
PAINT GREEN (-1320 1832);
DISPLAY INVISIBLE (-1320 1832);
FORCEPROP 1 LAST PATH I33
J 0
(-1200 1875);
DISPLAY 0.872340 (-1200 1875);
PAINT AQUA (-1200 1875);
DISPLAY INVISIBLE (-1200 1875);
FORCEPROP 2 LAST ROOM PVMCP_FPGA_CPU0_VR
J 0
(-1825 1950);
DISPLAY 3.127660 (-1825 1950);
PAINT WHITE (-1825 1950);
DISPLAY INVISIBLE (-1825 1950);
FORCEPROP 1 LAST HDL_POWER GND
J 0
(-1275 2025);
DISPLAY 2.787234 (-1275 2025);
PAINT GREEN (-1275 2025);
DISPLAY INVISIBLE (-1275 2025);
FORCEADD SCONN120_H61426002..1
(-3150 2100);
FORCEPROP 1 LAST LOCATION J6E1
J 0
(-3500 4100);
DISPLAY 0.617021 (-3500 4100);
PAINT AQUA (-3500 4100);
FORCEPROP 1 LAST PART_NUMBER H61426-002
J 0
(-3500 200);
DISPLAY 0.617021 (-3500 200);
PAINT BLUE (-3500 200);
FORCEPROP 1 LAST MATERIAL CONN
J 0
(-3500 4050);
DISPLAY 0.617021 (-3500 4050);
PAINT SKYBLUE (-3500 4050);
FORCEPROP 2 LASTPIN (-2750 400) $PN F20
J 0
(-2740 410);
DISPLAY 0.617021 (-2740 410);
PAINT ORANGE (-2740 410);
FORCEPROP 2 LASTPIN (-2750 750) $PN F19
J 0
(-2740 760);
DISPLAY 0.617021 (-2740 760);
PAINT ORANGE (-2740 760);
FORCEPROP 2 LASTPIN (-2750 1100) $PN F18
J 0
(-2740 1110);
DISPLAY 0.617021 (-2740 1110);
PAINT ORANGE (-2740 1110);
FORCEPROP 2 LASTPIN (-2750 1450) $PN F17
J 0
(-2740 1460);
DISPLAY 0.617021 (-2740 1460);
PAINT ORANGE (-2740 1460);
FORCEPROP 2 LASTPIN (-2750 1800) $PN F16
J 0
(-2740 1810);
DISPLAY 0.617021 (-2740 1810);
PAINT ORANGE (-2740 1810);
FORCEPROP 2 LASTPIN (-2750 2150) $PN F15
J 0
(-2740 2160);
DISPLAY 0.617021 (-2740 2160);
PAINT ORANGE (-2740 2160);
FORCEPROP 2 LASTPIN (-2750 2500) $PN F14
J 0
(-2740 2510);
DISPLAY 0.617021 (-2740 2510);
PAINT ORANGE (-2740 2510);
FORCEPROP 2 LASTPIN (-2750 2850) $PN F13
J 0
(-2740 2860);
DISPLAY 0.617021 (-2740 2860);
PAINT ORANGE (-2740 2860);
FORCEPROP 2 LASTPIN (-2750 3200) $PN F12
J 0
(-2740 3210);
DISPLAY 0.617021 (-2740 3210);
PAINT ORANGE (-2740 3210);
FORCEPROP 2 LASTPIN (-2750 3550) $PN F11
J 0
(-2740 3560);
DISPLAY 0.617021 (-2740 3560);
PAINT ORANGE (-2740 3560);
FORCEPROP 2 LASTPIN (-3550 400) $PN F10
J 2
(-3560 410);
DISPLAY 0.617021 (-3560 410);
PAINT ORANGE (-3560 410);
FORCEPROP 2 LASTPIN (-3550 750) $PN F9
J 2
(-3560 760);
DISPLAY 0.617021 (-3560 760);
PAINT ORANGE (-3560 760);
FORCEPROP 2 LASTPIN (-3550 1100) $PN F8
J 2
(-3560 1110);
DISPLAY 0.617021 (-3560 1110);
PAINT ORANGE (-3560 1110);
FORCEPROP 2 LASTPIN (-3550 1450) $PN F7
J 2
(-3560 1460);
DISPLAY 0.617021 (-3560 1460);
PAINT ORANGE (-3560 1460);
FORCEPROP 2 LASTPIN (-3550 1800) $PN F6
J 2
(-3560 1810);
DISPLAY 0.617021 (-3560 1810);
PAINT ORANGE (-3560 1810);
FORCEPROP 2 LASTPIN (-3550 2150) $PN F5
J 2
(-3560 2160);
DISPLAY 0.617021 (-3560 2160);
PAINT ORANGE (-3560 2160);
FORCEPROP 2 LASTPIN (-3550 2500) $PN F4
J 2
(-3560 2510);
DISPLAY 0.617021 (-3560 2510);
PAINT ORANGE (-3560 2510);
FORCEPROP 2 LASTPIN (-3550 2850) $PN F3
J 2
(-3560 2860);
DISPLAY 0.617021 (-3560 2860);
PAINT ORANGE (-3560 2860);
FORCEPROP 2 LASTPIN (-3550 3200) $PN F2
J 2
(-3560 3210);
DISPLAY 0.617021 (-3560 3210);
PAINT ORANGE (-3560 3210);
FORCEPROP 2 LASTPIN (-3550 3550) $PN F1
J 2
(-3560 3560);
DISPLAY 0.617021 (-3560 3560);
PAINT ORANGE (-3560 3560);
FORCEPROP 2 LASTPIN (-2750 450) $PN E20
J 0
(-2740 460);
DISPLAY 0.617021 (-2740 460);
PAINT ORANGE (-2740 460);
FORCEPROP 2 LASTPIN (-2750 800) $PN E19
J 0
(-2740 810);
DISPLAY 0.617021 (-2740 810);
PAINT ORANGE (-2740 810);
FORCEPROP 2 LASTPIN (-2750 1150) $PN E18
J 0
(-2740 1160);
DISPLAY 0.617021 (-2740 1160);
PAINT ORANGE (-2740 1160);
FORCEPROP 2 LASTPIN (-2750 1500) $PN E17
J 0
(-2740 1510);
DISPLAY 0.617021 (-2740 1510);
PAINT ORANGE (-2740 1510);
FORCEPROP 2 LASTPIN (-2750 1850) $PN E16
J 0
(-2740 1860);
DISPLAY 0.617021 (-2740 1860);
PAINT ORANGE (-2740 1860);
FORCEPROP 2 LASTPIN (-2750 2200) $PN E15
J 0
(-2740 2210);
DISPLAY 0.617021 (-2740 2210);
PAINT ORANGE (-2740 2210);
FORCEPROP 2 LASTPIN (-2750 2550) $PN E14
J 0
(-2740 2560);
DISPLAY 0.617021 (-2740 2560);
PAINT ORANGE (-2740 2560);
FORCEPROP 2 LASTPIN (-2750 2900) $PN E13
J 0
(-2740 2910);
DISPLAY 0.617021 (-2740 2910);
PAINT ORANGE (-2740 2910);
FORCEPROP 2 LASTPIN (-2750 3250) $PN E12
J 0
(-2740 3260);
DISPLAY 0.617021 (-2740 3260);
PAINT ORANGE (-2740 3260);
FORCEPROP 2 LASTPIN (-2750 3600) $PN E11
J 0
(-2740 3610);
DISPLAY 0.617021 (-2740 3610);
PAINT ORANGE (-2740 3610);
FORCEPROP 2 LASTPIN (-3550 450) $PN E10
J 2
(-3560 460);
DISPLAY 0.617021 (-3560 460);
PAINT ORANGE (-3560 460);
FORCEPROP 2 LASTPIN (-3550 800) $PN E9
J 2
(-3560 810);
DISPLAY 0.617021 (-3560 810);
PAINT ORANGE (-3560 810);
FORCEPROP 2 LASTPIN (-3550 1150) $PN E8
J 2
(-3560 1160);
DISPLAY 0.617021 (-3560 1160);
PAINT ORANGE (-3560 1160);
FORCEPROP 2 LASTPIN (-3550 1500) $PN E7
J 2
(-3560 1510);
DISPLAY 0.617021 (-3560 1510);
PAINT ORANGE (-3560 1510);
FORCEPROP 2 LASTPIN (-3550 1850) $PN E6
J 2
(-3560 1860);
DISPLAY 0.617021 (-3560 1860);
PAINT ORANGE (-3560 1860);
FORCEPROP 2 LASTPIN (-3550 2200) $PN E5
J 2
(-3560 2210);
DISPLAY 0.617021 (-3560 2210);
PAINT ORANGE (-3560 2210);
FORCEPROP 2 LASTPIN (-3550 2550) $PN E4
J 2
(-3560 2560);
DISPLAY 0.617021 (-3560 2560);
PAINT ORANGE (-3560 2560);
FORCEPROP 2 LASTPIN (-3550 2900) $PN E3
J 2
(-3560 2910);
DISPLAY 0.617021 (-3560 2910);
PAINT ORANGE (-3560 2910);
FORCEPROP 2 LASTPIN (-3550 3250) $PN E2
J 2
(-3560 3260);
DISPLAY 0.617021 (-3560 3260);
PAINT ORANGE (-3560 3260);
FORCEPROP 2 LASTPIN (-3550 3600) $PN E1
J 2
(-3560 3610);
DISPLAY 0.617021 (-3560 3610);
PAINT ORANGE (-3560 3610);
FORCEPROP 2 LASTPIN (-2750 500) $PN D20
J 0
(-2740 510);
DISPLAY 0.617021 (-2740 510);
PAINT ORANGE (-2740 510);
FORCEPROP 2 LASTPIN (-2750 850) $PN D19
J 0
(-2740 860);
DISPLAY 0.617021 (-2740 860);
PAINT ORANGE (-2740 860);
FORCEPROP 2 LASTPIN (-2750 1200) $PN D18
J 0
(-2740 1210);
DISPLAY 0.617021 (-2740 1210);
PAINT ORANGE (-2740 1210);
FORCEPROP 2 LASTPIN (-2750 1550) $PN D17
J 0
(-2740 1560);
DISPLAY 0.617021 (-2740 1560);
PAINT ORANGE (-2740 1560);
FORCEPROP 2 LASTPIN (-2750 1900) $PN D16
J 0
(-2740 1910);
DISPLAY 0.617021 (-2740 1910);
PAINT ORANGE (-2740 1910);
FORCEPROP 2 LASTPIN (-2750 2250) $PN D15
J 0
(-2740 2260);
DISPLAY 0.617021 (-2740 2260);
PAINT ORANGE (-2740 2260);
FORCEPROP 2 LASTPIN (-2750 2600) $PN D14
J 0
(-2740 2610);
DISPLAY 0.617021 (-2740 2610);
PAINT ORANGE (-2740 2610);
FORCEPROP 2 LASTPIN (-2750 2950) $PN D13
J 0
(-2740 2960);
DISPLAY 0.617021 (-2740 2960);
PAINT ORANGE (-2740 2960);
FORCEPROP 2 LASTPIN (-2750 3300) $PN D12
J 0
(-2740 3310);
DISPLAY 0.617021 (-2740 3310);
PAINT ORANGE (-2740 3310);
FORCEPROP 2 LASTPIN (-2750 3650) $PN D11
J 0
(-2740 3660);
DISPLAY 0.617021 (-2740 3660);
PAINT ORANGE (-2740 3660);
FORCEPROP 2 LASTPIN (-3550 500) $PN D10
J 2
(-3560 510);
DISPLAY 0.617021 (-3560 510);
PAINT ORANGE (-3560 510);
FORCEPROP 2 LASTPIN (-3550 850) $PN D9
J 2
(-3560 860);
DISPLAY 0.617021 (-3560 860);
PAINT ORANGE (-3560 860);
FORCEPROP 2 LASTPIN (-3550 1200) $PN D8
J 2
(-3560 1210);
DISPLAY 0.617021 (-3560 1210);
PAINT ORANGE (-3560 1210);
FORCEPROP 2 LASTPIN (-3550 1550) $PN D7
J 2
(-3560 1560);
DISPLAY 0.617021 (-3560 1560);
PAINT ORANGE (-3560 1560);
FORCEPROP 2 LASTPIN (-3550 1900) $PN D6
J 2
(-3560 1910);
DISPLAY 0.617021 (-3560 1910);
PAINT ORANGE (-3560 1910);
FORCEPROP 2 LASTPIN (-3550 2250) $PN D5
J 2
(-3560 2260);
DISPLAY 0.617021 (-3560 2260);
PAINT ORANGE (-3560 2260);
FORCEPROP 2 LASTPIN (-3550 2600) $PN D4
J 2
(-3560 2610);
DISPLAY 0.617021 (-3560 2610);
PAINT ORANGE (-3560 2610);
FORCEPROP 2 LASTPIN (-3550 2950) $PN D3
J 2
(-3560 2960);
DISPLAY 0.617021 (-3560 2960);
PAINT ORANGE (-3560 2960);
FORCEPROP 2 LASTPIN (-3550 3300) $PN D2
J 2
(-3560 3310);
DISPLAY 0.617021 (-3560 3310);
PAINT ORANGE (-3560 3310);
FORCEPROP 2 LASTPIN (-3550 3650) $PN D1
J 2
(-3560 3660);
DISPLAY 0.617021 (-3560 3660);
PAINT ORANGE (-3560 3660);
FORCEPROP 2 LASTPIN (-2750 550) $PN C20
J 0
(-2740 560);
DISPLAY 0.617021 (-2740 560);
PAINT ORANGE (-2740 560);
FORCEPROP 2 LASTPIN (-2750 900) $PN C19
J 0
(-2740 910);
DISPLAY 0.617021 (-2740 910);
PAINT ORANGE (-2740 910);
FORCEPROP 2 LASTPIN (-2750 1250) $PN C18
J 0
(-2740 1260);
DISPLAY 0.617021 (-2740 1260);
PAINT ORANGE (-2740 1260);
FORCEPROP 2 LASTPIN (-2750 1600) $PN C17
J 0
(-2740 1610);
DISPLAY 0.617021 (-2740 1610);
PAINT ORANGE (-2740 1610);
FORCEPROP 2 LASTPIN (-2750 1950) $PN C16
J 0
(-2740 1960);
DISPLAY 0.617021 (-2740 1960);
PAINT ORANGE (-2740 1960);
FORCEPROP 2 LASTPIN (-2750 2300) $PN C15
J 0
(-2740 2310);
DISPLAY 0.617021 (-2740 2310);
PAINT ORANGE (-2740 2310);
FORCEPROP 2 LASTPIN (-2750 2650) $PN C14
J 0
(-2740 2660);
DISPLAY 0.617021 (-2740 2660);
PAINT ORANGE (-2740 2660);
FORCEPROP 2 LASTPIN (-2750 3000) $PN C13
J 0
(-2740 3010);
DISPLAY 0.617021 (-2740 3010);
PAINT ORANGE (-2740 3010);
FORCEPROP 2 LASTPIN (-2750 3350) $PN C12
J 0
(-2740 3360);
DISPLAY 0.617021 (-2740 3360);
PAINT ORANGE (-2740 3360);
FORCEPROP 2 LASTPIN (-2750 3700) $PN C11
J 0
(-2740 3710);
DISPLAY 0.617021 (-2740 3710);
PAINT ORANGE (-2740 3710);
FORCEPROP 2 LASTPIN (-3550 550) $PN C10
J 2
(-3560 560);
DISPLAY 0.617021 (-3560 560);
PAINT ORANGE (-3560 560);
FORCEPROP 2 LASTPIN (-3550 900) $PN C9
J 2
(-3560 910);
DISPLAY 0.617021 (-3560 910);
PAINT ORANGE (-3560 910);
FORCEPROP 2 LASTPIN (-3550 1250) $PN C8
J 2
(-3560 1260);
DISPLAY 0.617021 (-3560 1260);
PAINT ORANGE (-3560 1260);
FORCEPROP 2 LASTPIN (-3550 1600) $PN C7
J 2
(-3560 1610);
DISPLAY 0.617021 (-3560 1610);
PAINT ORANGE (-3560 1610);
FORCEPROP 2 LASTPIN (-3550 1950) $PN C6
J 2
(-3560 1960);
DISPLAY 0.617021 (-3560 1960);
PAINT ORANGE (-3560 1960);
FORCEPROP 2 LASTPIN (-3550 2300) $PN C5
J 2
(-3560 2310);
DISPLAY 0.617021 (-3560 2310);
PAINT ORANGE (-3560 2310);
FORCEPROP 2 LASTPIN (-3550 2650) $PN C4
J 2
(-3560 2660);
DISPLAY 0.617021 (-3560 2660);
PAINT ORANGE (-3560 2660);
FORCEPROP 2 LASTPIN (-3550 3000) $PN C3
J 2
(-3560 3010);
DISPLAY 0.617021 (-3560 3010);
PAINT ORANGE (-3560 3010);
FORCEPROP 2 LASTPIN (-3550 3350) $PN C2
J 2
(-3560 3360);
DISPLAY 0.617021 (-3560 3360);
PAINT ORANGE (-3560 3360);
FORCEPROP 2 LASTPIN (-3550 3700) $PN C1
J 2
(-3560 3710);
DISPLAY 0.617021 (-3560 3710);
PAINT ORANGE (-3560 3710);
FORCEPROP 2 LASTPIN (-2750 600) $PN B20
J 0
(-2740 610);
DISPLAY 0.617021 (-2740 610);
PAINT ORANGE (-2740 610);
FORCEPROP 2 LASTPIN (-2750 950) $PN B19
J 0
(-2740 960);
DISPLAY 0.617021 (-2740 960);
PAINT ORANGE (-2740 960);
FORCEPROP 2 LASTPIN (-2750 1300) $PN B18
J 0
(-2740 1310);
DISPLAY 0.617021 (-2740 1310);
PAINT ORANGE (-2740 1310);
FORCEPROP 2 LASTPIN (-2750 1650) $PN B17
J 0
(-2740 1660);
DISPLAY 0.617021 (-2740 1660);
PAINT ORANGE (-2740 1660);
FORCEPROP 2 LASTPIN (-2750 2000) $PN B16
J 0
(-2740 2010);
DISPLAY 0.617021 (-2740 2010);
PAINT ORANGE (-2740 2010);
FORCEPROP 2 LASTPIN (-2750 2350) $PN B15
J 0
(-2740 2360);
DISPLAY 0.617021 (-2740 2360);
PAINT ORANGE (-2740 2360);
FORCEPROP 2 LASTPIN (-2750 2700) $PN B14
J 0
(-2740 2710);
DISPLAY 0.617021 (-2740 2710);
PAINT ORANGE (-2740 2710);
FORCEPROP 2 LASTPIN (-2750 3050) $PN B13
J 0
(-2740 3060);
DISPLAY 0.617021 (-2740 3060);
PAINT ORANGE (-2740 3060);
FORCEPROP 2 LASTPIN (-2750 3400) $PN B12
J 0
(-2740 3410);
DISPLAY 0.617021 (-2740 3410);
PAINT ORANGE (-2740 3410);
FORCEPROP 2 LASTPIN (-2750 3750) $PN B11
J 0
(-2740 3760);
DISPLAY 0.617021 (-2740 3760);
PAINT ORANGE (-2740 3760);
FORCEPROP 2 LASTPIN (-3550 600) $PN B10
J 2
(-3560 610);
DISPLAY 0.617021 (-3560 610);
PAINT ORANGE (-3560 610);
FORCEPROP 2 LASTPIN (-3550 950) $PN B9
J 2
(-3560 960);
DISPLAY 0.617021 (-3560 960);
PAINT ORANGE (-3560 960);
FORCEPROP 2 LASTPIN (-3550 1300) $PN B8
J 2
(-3560 1310);
DISPLAY 0.617021 (-3560 1310);
PAINT ORANGE (-3560 1310);
FORCEPROP 2 LASTPIN (-3550 1650) $PN B7
J 2
(-3560 1660);
DISPLAY 0.617021 (-3560 1660);
PAINT ORANGE (-3560 1660);
FORCEPROP 2 LASTPIN (-3550 2000) $PN B6
J 2
(-3560 2010);
DISPLAY 0.617021 (-3560 2010);
PAINT ORANGE (-3560 2010);
FORCEPROP 2 LASTPIN (-3550 2350) $PN B5
J 2
(-3560 2360);
DISPLAY 0.617021 (-3560 2360);
PAINT ORANGE (-3560 2360);
FORCEPROP 2 LASTPIN (-3550 2700) $PN B4
J 2
(-3560 2710);
DISPLAY 0.617021 (-3560 2710);
PAINT ORANGE (-3560 2710);
FORCEPROP 2 LASTPIN (-3550 3050) $PN B3
J 2
(-3560 3060);
DISPLAY 0.617021 (-3560 3060);
PAINT ORANGE (-3560 3060);
FORCEPROP 2 LASTPIN (-3550 3400) $PN B2
J 2
(-3560 3410);
DISPLAY 0.617021 (-3560 3410);
PAINT ORANGE (-3560 3410);
FORCEPROP 2 LASTPIN (-3550 3750) $PN B1
J 2
(-3560 3760);
DISPLAY 0.617021 (-3560 3760);
PAINT ORANGE (-3560 3760);
FORCEPROP 2 LASTPIN (-2750 650) $PN A20
J 0
(-2740 660);
DISPLAY 0.617021 (-2740 660);
PAINT ORANGE (-2740 660);
FORCEPROP 2 LASTPIN (-2750 1000) $PN A19
J 0
(-2740 1010);
DISPLAY 0.617021 (-2740 1010);
PAINT ORANGE (-2740 1010);
FORCEPROP 2 LASTPIN (-2750 1350) $PN A18
J 0
(-2740 1360);
DISPLAY 0.617021 (-2740 1360);
PAINT ORANGE (-2740 1360);
FORCEPROP 2 LASTPIN (-2750 1700) $PN A17
J 0
(-2740 1710);
DISPLAY 0.617021 (-2740 1710);
PAINT ORANGE (-2740 1710);
FORCEPROP 2 LASTPIN (-2750 2050) $PN A16
J 0
(-2740 2060);
DISPLAY 0.617021 (-2740 2060);
PAINT ORANGE (-2740 2060);
FORCEPROP 2 LASTPIN (-2750 2400) $PN A15
J 0
(-2740 2410);
DISPLAY 0.617021 (-2740 2410);
PAINT ORANGE (-2740 2410);
FORCEPROP 2 LASTPIN (-2750 2750) $PN A14
J 0
(-2740 2760);
DISPLAY 0.617021 (-2740 2760);
PAINT ORANGE (-2740 2760);
FORCEPROP 2 LASTPIN (-2750 3100) $PN A13
J 0
(-2740 3110);
DISPLAY 0.617021 (-2740 3110);
PAINT ORANGE (-2740 3110);
FORCEPROP 2 LASTPIN (-2750 3450) $PN A12
J 0
(-2740 3460);
DISPLAY 0.617021 (-2740 3460);
PAINT ORANGE (-2740 3460);
FORCEPROP 2 LASTPIN (-2750 3800) $PN A11
J 0
(-2740 3810);
DISPLAY 0.617021 (-2740 3810);
PAINT ORANGE (-2740 3810);
FORCEPROP 2 LASTPIN (-3550 650) $PN A10
J 2
(-3560 660);
DISPLAY 0.617021 (-3560 660);
PAINT ORANGE (-3560 660);
FORCEPROP 2 LASTPIN (-3550 1000) $PN A9
J 2
(-3560 1010);
DISPLAY 0.617021 (-3560 1010);
PAINT ORANGE (-3560 1010);
FORCEPROP 2 LASTPIN (-3550 1350) $PN A8
J 2
(-3560 1360);
DISPLAY 0.617021 (-3560 1360);
PAINT ORANGE (-3560 1360);
FORCEPROP 2 LASTPIN (-3550 1700) $PN A7
J 2
(-3560 1710);
DISPLAY 0.617021 (-3560 1710);
PAINT ORANGE (-3560 1710);
FORCEPROP 2 LASTPIN (-3550 2050) $PN A6
J 2
(-3560 2060);
DISPLAY 0.617021 (-3560 2060);
PAINT ORANGE (-3560 2060);
FORCEPROP 2 LASTPIN (-3550 2400) $PN A5
J 2
(-3560 2410);
DISPLAY 0.617021 (-3560 2410);
PAINT ORANGE (-3560 2410);
FORCEPROP 2 LASTPIN (-3550 2750) $PN A4
J 2
(-3560 2760);
DISPLAY 0.617021 (-3560 2760);
PAINT ORANGE (-3560 2760);
FORCEPROP 2 LASTPIN (-3550 3100) $PN A3
J 2
(-3560 3110);
DISPLAY 0.617021 (-3560 3110);
PAINT ORANGE (-3560 3110);
FORCEPROP 2 LASTPIN (-3550 3450) $PN A2
J 2
(-3560 3460);
DISPLAY 0.617021 (-3560 3460);
PAINT ORANGE (-3560 3460);
FORCEPROP 2 LASTPIN (-3550 3800) $PN A1
J 2
(-3560 3810);
DISPLAY 0.617021 (-3560 3810);
PAINT ORANGE (-3560 3810);
FORCEPROP 0 LAST ROOM MCP VRM CPU0
J 0
(-3375 4025);
DISPLAY 0.617021 (-3375 4025);
PAINT ORANGE (-3375 4025);
FORCEPROP 1 LAST PACK_TYPE SM
J 0
(-3500 4150);
PAINT SKYBLUE (-3500 4150);
DISPLAY INVISIBLE (-3500 4150);
FORCEPROP 2 LAST SEC_TYPE SM
J 0
(-3500 4150);
DISPLAY 1.021277 (-3500 4150);
PAINT ORANGE (-3500 4150);
DISPLAY INVISIBLE (-3500 4150);
FORCEPROP 2 LAST CDS_LIB mstr_sconn
J 0
(-3150 2100);
PAINT ORANGE (-3150 2100);
DISPLAY INVISIBLE (-3150 2100);
FORCEPROP 2 LAST SEC 1
J 0
(-3500 4150);
DISPLAY 0.680851 (-3500 4150);
PAINT MONO (-3500 4150);
DISPLAY INVISIBLE (-3500 4150);
FORCEPROP 2 LAST CDS_LOCATION J6E1
J 0
(-3500 4100);
DISPLAY 0.617021 (-3500 4100);
PAINT AQUA (-3500 4100);
DISPLAY INVISIBLE (-3500 4100);
FORCEPROP 1 LAST PATH I55
J 0
(-3100 4050);
PAINT GREEN (-3100 4050);
DISPLAY INVISIBLE (-3100 4050);
FORCEADD SCONN120_H61426002..1
(-6550 2075);
FORCEPROP 1 LAST LOCATION J6B1
J 0
(-6900 4075);
DISPLAY 0.617021 (-6900 4075);
PAINT AQUA (-6900 4075);
FORCEPROP 1 LAST PART_NUMBER H61426-002
J 0
(-6900 175);
DISPLAY 0.617021 (-6900 175);
PAINT BLUE (-6900 175);
FORCEPROP 1 LAST MATERIAL CONN
J 0
(-6900 4025);
DISPLAY 0.617021 (-6900 4025);
PAINT SKYBLUE (-6900 4025);
FORCEPROP 2 LASTPIN (-6150 375) $PN F20
J 0
(-6140 385);
DISPLAY 0.617021 (-6140 385);
PAINT ORANGE (-6140 385);
FORCEPROP 2 LASTPIN (-6150 725) $PN F19
J 0
(-6140 735);
DISPLAY 0.617021 (-6140 735);
PAINT ORANGE (-6140 735);
FORCEPROP 2 LASTPIN (-6150 1075) $PN F18
J 0
(-6140 1085);
DISPLAY 0.617021 (-6140 1085);
PAINT ORANGE (-6140 1085);
FORCEPROP 2 LASTPIN (-6150 1425) $PN F17
J 0
(-6140 1435);
DISPLAY 0.617021 (-6140 1435);
PAINT ORANGE (-6140 1435);
FORCEPROP 2 LASTPIN (-6150 1775) $PN F16
J 0
(-6140 1785);
DISPLAY 0.617021 (-6140 1785);
PAINT ORANGE (-6140 1785);
FORCEPROP 2 LASTPIN (-6150 2125) $PN F15
J 0
(-6140 2135);
DISPLAY 0.617021 (-6140 2135);
PAINT ORANGE (-6140 2135);
FORCEPROP 2 LASTPIN (-6150 2475) $PN F14
J 0
(-6140 2485);
DISPLAY 0.617021 (-6140 2485);
PAINT ORANGE (-6140 2485);
FORCEPROP 2 LASTPIN (-6150 2825) $PN F13
J 0
(-6140 2835);
DISPLAY 0.617021 (-6140 2835);
PAINT ORANGE (-6140 2835);
FORCEPROP 2 LASTPIN (-6150 3175) $PN F12
J 0
(-6140 3185);
DISPLAY 0.617021 (-6140 3185);
PAINT ORANGE (-6140 3185);
FORCEPROP 2 LASTPIN (-6150 3525) $PN F11
J 0
(-6140 3535);
DISPLAY 0.617021 (-6140 3535);
PAINT ORANGE (-6140 3535);
FORCEPROP 2 LASTPIN (-6950 375) $PN F10
J 2
(-6960 385);
DISPLAY 0.617021 (-6960 385);
PAINT ORANGE (-6960 385);
FORCEPROP 2 LASTPIN (-6950 725) $PN F9
J 2
(-6960 735);
DISPLAY 0.617021 (-6960 735);
PAINT ORANGE (-6960 735);
FORCEPROP 2 LASTPIN (-6950 1075) $PN F8
J 2
(-6960 1085);
DISPLAY 0.617021 (-6960 1085);
PAINT ORANGE (-6960 1085);
FORCEPROP 2 LASTPIN (-6950 1425) $PN F7
J 2
(-6960 1435);
DISPLAY 0.617021 (-6960 1435);
PAINT ORANGE (-6960 1435);
FORCEPROP 2 LASTPIN (-6950 1775) $PN F6
J 2
(-6960 1785);
DISPLAY 0.617021 (-6960 1785);
PAINT ORANGE (-6960 1785);
FORCEPROP 2 LASTPIN (-6950 2125) $PN F5
J 2
(-6960 2135);
DISPLAY 0.617021 (-6960 2135);
PAINT ORANGE (-6960 2135);
FORCEPROP 2 LASTPIN (-6950 2475) $PN F4
J 2
(-6960 2485);
DISPLAY 0.617021 (-6960 2485);
PAINT ORANGE (-6960 2485);
FORCEPROP 2 LASTPIN (-6950 2825) $PN F3
J 2
(-6960 2835);
DISPLAY 0.617021 (-6960 2835);
PAINT ORANGE (-6960 2835);
FORCEPROP 2 LASTPIN (-6950 3175) $PN F2
J 2
(-6960 3185);
DISPLAY 0.617021 (-6960 3185);
PAINT ORANGE (-6960 3185);
FORCEPROP 2 LASTPIN (-6950 3525) $PN F1
J 2
(-6960 3535);
DISPLAY 0.617021 (-6960 3535);
PAINT ORANGE (-6960 3535);
FORCEPROP 2 LASTPIN (-6150 425) $PN E20
J 0
(-6140 435);
DISPLAY 0.617021 (-6140 435);
PAINT ORANGE (-6140 435);
FORCEPROP 2 LASTPIN (-6150 775) $PN E19
J 0
(-6140 785);
DISPLAY 0.617021 (-6140 785);
PAINT ORANGE (-6140 785);
FORCEPROP 2 LASTPIN (-6150 1125) $PN E18
J 0
(-6140 1135);
DISPLAY 0.617021 (-6140 1135);
PAINT ORANGE (-6140 1135);
FORCEPROP 2 LASTPIN (-6150 1475) $PN E17
J 0
(-6140 1485);
DISPLAY 0.617021 (-6140 1485);
PAINT ORANGE (-6140 1485);
FORCEPROP 2 LASTPIN (-6150 1825) $PN E16
J 0
(-6140 1835);
DISPLAY 0.617021 (-6140 1835);
PAINT ORANGE (-6140 1835);
FORCEPROP 2 LASTPIN (-6150 2175) $PN E15
J 0
(-6140 2185);
DISPLAY 0.617021 (-6140 2185);
PAINT ORANGE (-6140 2185);
FORCEPROP 2 LASTPIN (-6150 2525) $PN E14
J 0
(-6140 2535);
DISPLAY 0.617021 (-6140 2535);
PAINT ORANGE (-6140 2535);
FORCEPROP 2 LASTPIN (-6150 2875) $PN E13
J 0
(-6140 2885);
DISPLAY 0.617021 (-6140 2885);
PAINT ORANGE (-6140 2885);
FORCEPROP 2 LASTPIN (-6150 3225) $PN E12
J 0
(-6140 3235);
DISPLAY 0.617021 (-6140 3235);
PAINT ORANGE (-6140 3235);
FORCEPROP 2 LASTPIN (-6150 3575) $PN E11
J 0
(-6140 3585);
DISPLAY 0.617021 (-6140 3585);
PAINT ORANGE (-6140 3585);
FORCEPROP 2 LASTPIN (-6950 425) $PN E10
J 2
(-6960 435);
DISPLAY 0.617021 (-6960 435);
PAINT ORANGE (-6960 435);
FORCEPROP 2 LASTPIN (-6950 775) $PN E9
J 2
(-6960 785);
DISPLAY 0.617021 (-6960 785);
PAINT ORANGE (-6960 785);
FORCEPROP 2 LASTPIN (-6950 1125) $PN E8
J 2
(-6960 1135);
DISPLAY 0.617021 (-6960 1135);
PAINT ORANGE (-6960 1135);
FORCEPROP 2 LASTPIN (-6950 1475) $PN E7
J 2
(-6960 1485);
DISPLAY 0.617021 (-6960 1485);
PAINT ORANGE (-6960 1485);
FORCEPROP 2 LASTPIN (-6950 1825) $PN E6
J 2
(-6960 1835);
DISPLAY 0.617021 (-6960 1835);
PAINT ORANGE (-6960 1835);
FORCEPROP 2 LASTPIN (-6950 2175) $PN E5
J 2
(-6960 2185);
DISPLAY 0.617021 (-6960 2185);
PAINT ORANGE (-6960 2185);
FORCEPROP 2 LASTPIN (-6950 2525) $PN E4
J 2
(-6960 2535);
DISPLAY 0.617021 (-6960 2535);
PAINT ORANGE (-6960 2535);
FORCEPROP 2 LASTPIN (-6950 2875) $PN E3
J 2
(-6960 2885);
DISPLAY 0.617021 (-6960 2885);
PAINT ORANGE (-6960 2885);
FORCEPROP 2 LASTPIN (-6950 3225) $PN E2
J 2
(-6960 3235);
DISPLAY 0.617021 (-6960 3235);
PAINT ORANGE (-6960 3235);
FORCEPROP 2 LASTPIN (-6950 3575) $PN E1
J 2
(-6960 3585);
DISPLAY 0.617021 (-6960 3585);
PAINT ORANGE (-6960 3585);
FORCEPROP 2 LASTPIN (-6150 475) $PN D20
J 0
(-6140 485);
DISPLAY 0.617021 (-6140 485);
PAINT ORANGE (-6140 485);
FORCEPROP 2 LASTPIN (-6150 825) $PN D19
J 0
(-6140 835);
DISPLAY 0.617021 (-6140 835);
PAINT ORANGE (-6140 835);
FORCEPROP 2 LASTPIN (-6150 1175) $PN D18
J 0
(-6140 1185);
DISPLAY 0.617021 (-6140 1185);
PAINT ORANGE (-6140 1185);
FORCEPROP 2 LASTPIN (-6150 1525) $PN D17
J 0
(-6140 1535);
DISPLAY 0.617021 (-6140 1535);
PAINT ORANGE (-6140 1535);
FORCEPROP 2 LASTPIN (-6150 1875) $PN D16
J 0
(-6140 1885);
DISPLAY 0.617021 (-6140 1885);
PAINT ORANGE (-6140 1885);
FORCEPROP 2 LASTPIN (-6150 2225) $PN D15
J 0
(-6140 2235);
DISPLAY 0.617021 (-6140 2235);
PAINT ORANGE (-6140 2235);
FORCEPROP 2 LASTPIN (-6150 2575) $PN D14
J 0
(-6140 2585);
DISPLAY 0.617021 (-6140 2585);
PAINT ORANGE (-6140 2585);
FORCEPROP 2 LASTPIN (-6150 2925) $PN D13
J 0
(-6140 2935);
DISPLAY 0.617021 (-6140 2935);
PAINT ORANGE (-6140 2935);
FORCEPROP 2 LASTPIN (-6150 3275) $PN D12
J 0
(-6140 3285);
DISPLAY 0.617021 (-6140 3285);
PAINT ORANGE (-6140 3285);
FORCEPROP 2 LASTPIN (-6150 3625) $PN D11
J 0
(-6140 3635);
DISPLAY 0.617021 (-6140 3635);
PAINT ORANGE (-6140 3635);
FORCEPROP 2 LASTPIN (-6950 475) $PN D10
J 2
(-6960 485);
DISPLAY 0.617021 (-6960 485);
PAINT ORANGE (-6960 485);
FORCEPROP 2 LASTPIN (-6950 825) $PN D9
J 2
(-6960 835);
DISPLAY 0.617021 (-6960 835);
PAINT ORANGE (-6960 835);
FORCEPROP 2 LASTPIN (-6950 1175) $PN D8
J 2
(-6960 1185);
DISPLAY 0.617021 (-6960 1185);
PAINT ORANGE (-6960 1185);
FORCEPROP 2 LASTPIN (-6950 1525) $PN D7
J 2
(-6960 1535);
DISPLAY 0.617021 (-6960 1535);
PAINT ORANGE (-6960 1535);
FORCEPROP 2 LASTPIN (-6950 1875) $PN D6
J 2
(-6960 1885);
DISPLAY 0.617021 (-6960 1885);
PAINT ORANGE (-6960 1885);
FORCEPROP 2 LASTPIN (-6950 2225) $PN D5
J 2
(-6960 2235);
DISPLAY 0.617021 (-6960 2235);
PAINT ORANGE (-6960 2235);
FORCEPROP 2 LASTPIN (-6950 2575) $PN D4
J 2
(-6960 2585);
DISPLAY 0.617021 (-6960 2585);
PAINT ORANGE (-6960 2585);
FORCEPROP 2 LASTPIN (-6950 2925) $PN D3
J 2
(-6960 2935);
DISPLAY 0.617021 (-6960 2935);
PAINT ORANGE (-6960 2935);
FORCEPROP 2 LASTPIN (-6950 3275) $PN D2
J 2
(-6960 3285);
DISPLAY 0.617021 (-6960 3285);
PAINT ORANGE (-6960 3285);
FORCEPROP 2 LASTPIN (-6950 3625) $PN D1
J 2
(-6960 3635);
DISPLAY 0.617021 (-6960 3635);
PAINT ORANGE (-6960 3635);
FORCEPROP 2 LASTPIN (-6150 525) $PN C20
J 0
(-6140 535);
DISPLAY 0.617021 (-6140 535);
PAINT ORANGE (-6140 535);
FORCEPROP 2 LASTPIN (-6150 875) $PN C19
J 0
(-6140 885);
DISPLAY 0.617021 (-6140 885);
PAINT ORANGE (-6140 885);
FORCEPROP 2 LASTPIN (-6150 1225) $PN C18
J 0
(-6140 1235);
DISPLAY 0.617021 (-6140 1235);
PAINT ORANGE (-6140 1235);
FORCEPROP 2 LASTPIN (-6150 1575) $PN C17
J 0
(-6140 1585);
DISPLAY 0.617021 (-6140 1585);
PAINT ORANGE (-6140 1585);
FORCEPROP 2 LASTPIN (-6150 1925) $PN C16
J 0
(-6140 1935);
DISPLAY 0.617021 (-6140 1935);
PAINT ORANGE (-6140 1935);
FORCEPROP 2 LASTPIN (-6150 2275) $PN C15
J 0
(-6140 2285);
DISPLAY 0.617021 (-6140 2285);
PAINT ORANGE (-6140 2285);
FORCEPROP 2 LASTPIN (-6150 2625) $PN C14
J 0
(-6140 2635);
DISPLAY 0.617021 (-6140 2635);
PAINT ORANGE (-6140 2635);
FORCEPROP 2 LASTPIN (-6150 2975) $PN C13
J 0
(-6140 2985);
DISPLAY 0.617021 (-6140 2985);
PAINT ORANGE (-6140 2985);
FORCEPROP 2 LASTPIN (-6150 3325) $PN C12
J 0
(-6140 3335);
DISPLAY 0.617021 (-6140 3335);
PAINT ORANGE (-6140 3335);
FORCEPROP 2 LASTPIN (-6150 3675) $PN C11
J 0
(-6140 3685);
DISPLAY 0.617021 (-6140 3685);
PAINT ORANGE (-6140 3685);
FORCEPROP 2 LASTPIN (-6950 525) $PN C10
J 2
(-6960 535);
DISPLAY 0.617021 (-6960 535);
PAINT ORANGE (-6960 535);
FORCEPROP 2 LASTPIN (-6950 875) $PN C9
J 2
(-6960 885);
DISPLAY 0.617021 (-6960 885);
PAINT ORANGE (-6960 885);
FORCEPROP 2 LASTPIN (-6950 1225) $PN C8
J 2
(-6960 1235);
DISPLAY 0.617021 (-6960 1235);
PAINT ORANGE (-6960 1235);
FORCEPROP 2 LASTPIN (-6950 1575) $PN C7
J 2
(-6960 1585);
DISPLAY 0.617021 (-6960 1585);
PAINT ORANGE (-6960 1585);
FORCEPROP 2 LASTPIN (-6950 1925) $PN C6
J 2
(-6960 1935);
DISPLAY 0.617021 (-6960 1935);
PAINT ORANGE (-6960 1935);
FORCEPROP 2 LASTPIN (-6950 2275) $PN C5
J 2
(-6960 2285);
DISPLAY 0.617021 (-6960 2285);
PAINT ORANGE (-6960 2285);
FORCEPROP 2 LASTPIN (-6950 2625) $PN C4
J 2
(-6960 2635);
DISPLAY 0.617021 (-6960 2635);
PAINT ORANGE (-6960 2635);
FORCEPROP 2 LASTPIN (-6950 2975) $PN C3
J 2
(-6960 2985);
DISPLAY 0.617021 (-6960 2985);
PAINT ORANGE (-6960 2985);
FORCEPROP 2 LASTPIN (-6950 3325) $PN C2
J 2
(-6960 3335);
DISPLAY 0.617021 (-6960 3335);
PAINT ORANGE (-6960 3335);
FORCEPROP 2 LASTPIN (-6950 3675) $PN C1
J 2
(-6960 3685);
DISPLAY 0.617021 (-6960 3685);
PAINT ORANGE (-6960 3685);
FORCEPROP 2 LASTPIN (-6150 575) $PN B20
J 0
(-6140 585);
DISPLAY 0.617021 (-6140 585);
PAINT ORANGE (-6140 585);
FORCEPROP 2 LASTPIN (-6150 925) $PN B19
J 0
(-6140 935);
DISPLAY 0.617021 (-6140 935);
PAINT ORANGE (-6140 935);
FORCEPROP 2 LASTPIN (-6150 1275) $PN B18
J 0
(-6140 1285);
DISPLAY 0.617021 (-6140 1285);
PAINT ORANGE (-6140 1285);
FORCEPROP 2 LASTPIN (-6150 1625) $PN B17
J 0
(-6140 1635);
DISPLAY 0.617021 (-6140 1635);
PAINT ORANGE (-6140 1635);
FORCEPROP 2 LASTPIN (-6150 1975) $PN B16
J 0
(-6140 1985);
DISPLAY 0.617021 (-6140 1985);
PAINT ORANGE (-6140 1985);
FORCEPROP 2 LASTPIN (-6150 2325) $PN B15
J 0
(-6140 2335);
DISPLAY 0.617021 (-6140 2335);
PAINT ORANGE (-6140 2335);
FORCEPROP 2 LASTPIN (-6150 2675) $PN B14
J 0
(-6140 2685);
DISPLAY 0.617021 (-6140 2685);
PAINT ORANGE (-6140 2685);
FORCEPROP 2 LASTPIN (-6150 3025) $PN B13
J 0
(-6140 3035);
DISPLAY 0.617021 (-6140 3035);
PAINT ORANGE (-6140 3035);
FORCEPROP 2 LASTPIN (-6150 3375) $PN B12
J 0
(-6140 3385);
DISPLAY 0.617021 (-6140 3385);
PAINT ORANGE (-6140 3385);
FORCEPROP 2 LASTPIN (-6150 3725) $PN B11
J 0
(-6140 3735);
DISPLAY 0.617021 (-6140 3735);
PAINT ORANGE (-6140 3735);
FORCEPROP 2 LASTPIN (-6950 575) $PN B10
J 2
(-6960 585);
DISPLAY 0.617021 (-6960 585);
PAINT ORANGE (-6960 585);
FORCEPROP 2 LASTPIN (-6950 925) $PN B9
J 2
(-6960 935);
DISPLAY 0.617021 (-6960 935);
PAINT ORANGE (-6960 935);
FORCEPROP 2 LASTPIN (-6950 1275) $PN B8
J 2
(-6960 1285);
DISPLAY 0.617021 (-6960 1285);
PAINT ORANGE (-6960 1285);
FORCEPROP 2 LASTPIN (-6950 1625) $PN B7
J 2
(-6960 1635);
DISPLAY 0.617021 (-6960 1635);
PAINT ORANGE (-6960 1635);
FORCEPROP 2 LASTPIN (-6950 1975) $PN B6
J 2
(-6960 1985);
DISPLAY 0.617021 (-6960 1985);
PAINT ORANGE (-6960 1985);
FORCEPROP 2 LASTPIN (-6950 2325) $PN B5
J 2
(-6960 2335);
DISPLAY 0.617021 (-6960 2335);
PAINT ORANGE (-6960 2335);
FORCEPROP 2 LASTPIN (-6950 2675) $PN B4
J 2
(-6960 2685);
DISPLAY 0.617021 (-6960 2685);
PAINT ORANGE (-6960 2685);
FORCEPROP 2 LASTPIN (-6950 3025) $PN B3
J 2
(-6960 3035);
DISPLAY 0.617021 (-6960 3035);
PAINT ORANGE (-6960 3035);
FORCEPROP 2 LASTPIN (-6950 3375) $PN B2
J 2
(-6960 3385);
DISPLAY 0.617021 (-6960 3385);
PAINT ORANGE (-6960 3385);
FORCEPROP 2 LASTPIN (-6950 3725) $PN B1
J 2
(-6960 3735);
DISPLAY 0.617021 (-6960 3735);
PAINT ORANGE (-6960 3735);
FORCEPROP 2 LASTPIN (-6150 625) $PN A20
J 0
(-6140 635);
DISPLAY 0.617021 (-6140 635);
PAINT ORANGE (-6140 635);
FORCEPROP 2 LASTPIN (-6150 975) $PN A19
J 0
(-6140 985);
DISPLAY 0.617021 (-6140 985);
PAINT ORANGE (-6140 985);
FORCEPROP 2 LASTPIN (-6150 1325) $PN A18
J 0
(-6140 1335);
DISPLAY 0.617021 (-6140 1335);
PAINT ORANGE (-6140 1335);
FORCEPROP 2 LASTPIN (-6150 1675) $PN A17
J 0
(-6140 1685);
DISPLAY 0.617021 (-6140 1685);
PAINT ORANGE (-6140 1685);
FORCEPROP 2 LASTPIN (-6150 2025) $PN A16
J 0
(-6140 2035);
DISPLAY 0.617021 (-6140 2035);
PAINT ORANGE (-6140 2035);
FORCEPROP 2 LASTPIN (-6150 2375) $PN A15
J 0
(-6140 2385);
DISPLAY 0.617021 (-6140 2385);
PAINT ORANGE (-6140 2385);
FORCEPROP 2 LASTPIN (-6150 2725) $PN A14
J 0
(-6140 2735);
DISPLAY 0.617021 (-6140 2735);
PAINT ORANGE (-6140 2735);
FORCEPROP 2 LASTPIN (-6150 3075) $PN A13
J 0
(-6140 3085);
DISPLAY 0.617021 (-6140 3085);
PAINT ORANGE (-6140 3085);
FORCEPROP 2 LASTPIN (-6150 3425) $PN A12
J 0
(-6140 3435);
DISPLAY 0.617021 (-6140 3435);
PAINT ORANGE (-6140 3435);
FORCEPROP 2 LASTPIN (-6150 3775) $PN A11
J 0
(-6140 3785);
DISPLAY 0.617021 (-6140 3785);
PAINT ORANGE (-6140 3785);
FORCEPROP 2 LASTPIN (-6950 625) $PN A10
J 2
(-6960 635);
DISPLAY 0.617021 (-6960 635);
PAINT ORANGE (-6960 635);
FORCEPROP 2 LASTPIN (-6950 975) $PN A9
J 2
(-6960 985);
DISPLAY 0.617021 (-6960 985);
PAINT ORANGE (-6960 985);
FORCEPROP 2 LASTPIN (-6950 1325) $PN A8
J 2
(-6960 1335);
DISPLAY 0.617021 (-6960 1335);
PAINT ORANGE (-6960 1335);
FORCEPROP 2 LASTPIN (-6950 1675) $PN A7
J 2
(-6960 1685);
DISPLAY 0.617021 (-6960 1685);
PAINT ORANGE (-6960 1685);
FORCEPROP 2 LASTPIN (-6950 2025) $PN A6
J 2
(-6960 2035);
DISPLAY 0.617021 (-6960 2035);
PAINT ORANGE (-6960 2035);
FORCEPROP 2 LASTPIN (-6950 2375) $PN A5
J 2
(-6960 2385);
DISPLAY 0.617021 (-6960 2385);
PAINT ORANGE (-6960 2385);
FORCEPROP 2 LASTPIN (-6950 2725) $PN A4
J 2
(-6960 2735);
DISPLAY 0.617021 (-6960 2735);
PAINT ORANGE (-6960 2735);
FORCEPROP 2 LASTPIN (-6950 3075) $PN A3
J 2
(-6960 3085);
DISPLAY 0.617021 (-6960 3085);
PAINT ORANGE (-6960 3085);
FORCEPROP 2 LASTPIN (-6950 3425) $PN A2
J 2
(-6960 3435);
DISPLAY 0.617021 (-6960 3435);
PAINT ORANGE (-6960 3435);
FORCEPROP 2 LASTPIN (-6950 3775) $PN A1
J 2
(-6960 3785);
DISPLAY 0.617021 (-6960 3785);
PAINT ORANGE (-6960 3785);
FORCEPROP 0 LAST ROOM MCP VRM CPU0
J 0
(-6725 4000);
DISPLAY 0.617021 (-6725 4000);
PAINT ORANGE (-6725 4000);
FORCEPROP 1 LAST PACK_TYPE SM
J 0
(-6900 4125);
PAINT SKYBLUE (-6900 4125);
DISPLAY INVISIBLE (-6900 4125);
FORCEPROP 2 LAST SEC_TYPE SM
J 0
(-6900 4125);
DISPLAY 1.021277 (-6900 4125);
PAINT ORANGE (-6900 4125);
DISPLAY INVISIBLE (-6900 4125);
FORCEPROP 2 LAST CDS_LIB mstr_sconn
J 0
(-6550 2075);
PAINT ORANGE (-6550 2075);
DISPLAY INVISIBLE (-6550 2075);
FORCEPROP 2 LAST SEC 1
J 0
(-6900 4125);
DISPLAY 0.680851 (-6900 4125);
PAINT MONO (-6900 4125);
DISPLAY INVISIBLE (-6900 4125);
FORCEPROP 2 LAST CDS_LOCATION J6B1
J 0
(-6900 4075);
DISPLAY 0.617021 (-6900 4075);
PAINT AQUA (-6900 4075);
DISPLAY INVISIBLE (-6900 4075);
FORCEPROP 1 LAST PATH I56
J 0
(-6500 4025);
PAINT GREEN (-6500 4025);
DISPLAY INVISIBLE (-6500 4025);
FORCEADD GND..1
(-3975 225);
FORCEPROP 3 LASTPIN (-3975 275) SIG_NAME GND\g
J 0
(-3965 285);
DISPLAY 0.659574 (-3965 285);
PAINT MONO (-3965 285);
DISPLAY INVISIBLE (-3965 285);
FORCEPROP 1 LAST VOLTAGE 0.0V
J 0
(-4020 182);
DISPLAY 0.340426 (-4020 182);
PAINT SKYBLUE (-4020 182);
DISPLAY INVISIBLE (-4020 182);
FORCEPROP 2 LAST CDS_LIB mstr_symbols
J 0
(-3975 225);
PAINT MONO (-3975 225);
DISPLAY INVISIBLE (-3975 225);
FORCEPROP 1 LAST SIZE 1B
J 0
(-3900 175);
DISPLAY 1.404255 (-3900 175);
PAINT AQUA (-3900 175);
DISPLAY INVISIBLE (-3900 175);
FORCEPROP 1 LAST BODY_TYPE PLUMBING
J 0
(-4020 182);
DISPLAY 0.340426 (-4020 182);
PAINT GREEN (-4020 182);
DISPLAY INVISIBLE (-4020 182);
FORCEPROP 1 LAST PATH I61
J 0
(-3900 225);
DISPLAY 0.872340 (-3900 225);
PAINT AQUA (-3900 225);
DISPLAY INVISIBLE (-3900 225);
FORCEPROP 1 LAST HDL_POWER GND
J 0
(-3975 375);
PAINT GREEN (-3975 375);
DISPLAY INVISIBLE (-3975 375);
FORCEADD GND..1
(-2150 200);
FORCEPROP 3 LASTPIN (-2150 250) SIG_NAME GND\g
J 0
(-2140 260);
DISPLAY 0.659574 (-2140 260);
PAINT MONO (-2140 260);
DISPLAY INVISIBLE (-2140 260);
FORCEPROP 1 LAST VOLTAGE 0.0V
J 0
(-2195 157);
DISPLAY 0.340426 (-2195 157);
PAINT SKYBLUE (-2195 157);
DISPLAY INVISIBLE (-2195 157);
FORCEPROP 1 LAST SIZE 1B
J 0
(-2075 150);
DISPLAY 1.404255 (-2075 150);
PAINT AQUA (-2075 150);
DISPLAY INVISIBLE (-2075 150);
FORCEPROP 2 LAST CDS_LIB mstr_symbols
J 0
(-2150 200);
PAINT MONO (-2150 200);
DISPLAY INVISIBLE (-2150 200);
FORCEPROP 1 LAST BODY_TYPE PLUMBING
J 0
(-2195 157);
DISPLAY 0.340426 (-2195 157);
PAINT GREEN (-2195 157);
DISPLAY INVISIBLE (-2195 157);
FORCEPROP 1 LAST PATH I62
J 0
(-2075 200);
DISPLAY 0.872340 (-2075 200);
PAINT AQUA (-2075 200);
DISPLAY INVISIBLE (-2075 200);
FORCEPROP 1 LAST HDL_POWER GND
J 0
(-2150 350);
PAINT GREEN (-2150 350);
DISPLAY INVISIBLE (-2150 350);
FORCEADD OFFPAGE..1
(-4650 2750);
FORCEPROP 2 LAST $XR0 39 
J 0
(-4901 2750);
DISPLAY 0.638298 (-4901 2750);
PAINT MONO (-4901 2750);
FORCEPROP 2 LAST CDS_LIB mstr_standard
J 0
(-4650 2750);
PAINT MONO (-4650 2750);
DISPLAY INVISIBLE (-4650 2750);
FORCEPROP 1 LAST OFFPAGE TRUE
J 0
(-4325 2625);
DISPLAY 1.170213 (-4325 2625);
PAINT GREEN (-4325 2625);
DISPLAY INVISIBLE (-4325 2625);
FORCEPROP 1 LAST COMMENT_BODY TRUE
J 0
(-4525 2650);
DISPLAY 1.170213 (-4525 2650);
PAINT GREEN (-4525 2650);
DISPLAY INVISIBLE (-4525 2650);
FORCEPROP 2 LAST PATH I64
J 0
(-4600 2825);
DISPLAY 1.021277 (-4600 2825);
PAINT ORANGE (-4600 2825);
DISPLAY INVISIBLE (-4600 2825);
FORCEADD OFFPAGE..1
(-4650 2700);
FORCEPROP 2 LAST $XR0 39 
J 0
(-4901 2700);
DISPLAY 0.638298 (-4901 2700);
PAINT MONO (-4901 2700);
FORCEPROP 2 LAST CDS_LIB mstr_standard
J 0
(-4650 2700);
PAINT MONO (-4650 2700);
DISPLAY INVISIBLE (-4650 2700);
FORCEPROP 1 LAST OFFPAGE TRUE
J 0
(-4325 2575);
DISPLAY 1.170213 (-4325 2575);
PAINT GREEN (-4325 2575);
DISPLAY INVISIBLE (-4325 2575);
FORCEPROP 1 LAST COMMENT_BODY TRUE
J 0
(-4525 2600);
DISPLAY 1.170213 (-4525 2600);
PAINT GREEN (-4525 2600);
DISPLAY INVISIBLE (-4525 2600);
FORCEPROP 2 LAST PATH I67
J 0
(-4600 2775);
DISPLAY 1.021277 (-4600 2775);
PAINT ORANGE (-4600 2775);
DISPLAY INVISIBLE (-4600 2775);
FORCEADD VCC_CORE..1
(-4925 3050);
FORCEPROP 3 LASTPIN (-4925 3000) SIG_NAME PVCCMCP_CPU0\g
J 0
(-4915 3010);
DISPLAY 0.659574 (-4915 3010);
PAINT MONO (-4915 3010);
DISPLAY INVISIBLE (-4915 3010);
FORCEPROP 1 LAST HDL_POWER PVCCMCP_CPU0
J 1
(-4925 3100);
DISPLAY 0.617021 (-4925 3100);
PAINT GREEN (-4925 3100);
FORCEPROP 2 LAST BOM_COST PVMCP_FPGA_CPU0_VR
J 0
(-4925 3150);
DISPLAY 2.340426 (-4925 3150);
PAINT WHITE (-4925 3150);
DISPLAY INVISIBLE (-4925 3150);
FORCEPROP 2 LAST CDS_LIB mstr_symbols
J 0
(-4925 3050);
PAINT MONO (-4925 3050);
DISPLAY INVISIBLE (-4925 3050);
FORCEPROP 1 LAST PATH I68
J 0
(-4875 3075);
DISPLAY 0.872340 (-4875 3075);
PAINT AQUA (-4875 3075);
DISPLAY INVISIBLE (-4875 3075);
FORCEPROP 2 LAST ROOM PVMCP_FPGA_CPU0_VR
J 0
(-4925 3150);
DISPLAY 3.127660 (-4925 3150);
PAINT WHITE (-4925 3150);
DISPLAY INVISIBLE (-4925 3150);
FORCEADD VCC_CORE..1
(-2300 3925);
FORCEPROP 3 LASTPIN (-2300 3875) SIG_NAME PVCCMCP_CPU0\g
J 0
(-2290 3885);
DISPLAY 0.659574 (-2290 3885);
PAINT MONO (-2290 3885);
DISPLAY INVISIBLE (-2290 3885);
FORCEPROP 1 LAST HDL_POWER PVCCMCP_CPU0
J 1
(-2300 3975);
DISPLAY 0.617021 (-2300 3975);
PAINT GREEN (-2300 3975);
FORCEPROP 2 LAST BOM_COST PVMCP_FPGA_CPU0_VR
J 0
(-2300 4025);
DISPLAY 2.340426 (-2300 4025);
PAINT WHITE (-2300 4025);
DISPLAY INVISIBLE (-2300 4025);
FORCEPROP 2 LAST CDS_LIB mstr_symbols
J 0
(-2300 3925);
PAINT MONO (-2300 3925);
DISPLAY INVISIBLE (-2300 3925);
FORCEPROP 1 LAST PATH I69
J 0
(-2250 3950);
DISPLAY 0.872340 (-2250 3950);
PAINT AQUA (-2250 3950);
DISPLAY INVISIBLE (-2250 3950);
FORCEPROP 2 LAST ROOM PVMCP_FPGA_CPU0_VR
J 0
(-2300 4025);
DISPLAY 3.127660 (-2300 4025);
PAINT WHITE (-2300 4025);
DISPLAY INVISIBLE (-2300 4025);
FORCEADD CAP_A..1
R 2
(-600 3250);
FORCEPROP 1 LAST LOCATION C3N40
J 2
(-650 3350);
DISPLAY 0.617021 (-650 3350);
PAINT AQUA (-650 3350);
FORCEPROP 1 LAST PART_NUMBER D97712-004
J 2
(-650 3100);
DISPLAY 0.617021 (-650 3100);
PAINT BLUE (-650 3100);
FORCEPROP 1 LAST VALUE 1.0UF
J 2
(-650 3300);
DISPLAY 0.617021 (-650 3300);
PAINT SKYBLUE (-650 3300);
FORCEPROP 1 LAST TOLERANCE 10%
J 2
(-650 3200);
DISPLAY 0.617021 (-650 3200);
PAINT SKYBLUE (-650 3200);
FORCEPROP 1 LAST PACK_TYPE 0402V
J 2
(-650 3050);
DISPLAY 0.617021 (-650 3050);
PAINT SKYBLUE (-650 3050);
FORCEPROP 1 LAST VOLTAGE 6.3V
J 2
(-650 3250);
DISPLAY 0.617021 (-650 3250);
PAINT SKYBLUE (-650 3250);
FORCEPROP 1 LAST MATERIAL X6S
J 2
(-650 3150);
DISPLAY 0.617021 (-650 3150);
PAINT SKYBLUE (-650 3150);
FORCEPROP 1 LASTPIN (-600 3350) $PN 1
J 2
(-610 3330);
DISPLAY 0.617021 (-610 3330);
PAINT ORANGE (-610 3330);
FORCEPROP 1 LASTPIN (-600 3150) $PN 2
J 2
(-610 3130);
DISPLAY 0.617021 (-610 3130);
PAINT ORANGE (-610 3130);
FORCEPROP 2 LAST CDS_LIB dev_discrete
J 0
(-600 3250);
PAINT ORANGE (-600 3250);
DISPLAY INVISIBLE (-600 3250);
FORCEPROP 2 LAST CDS_SEC 1
J 0
(-650 3400);
PAINT ORANGE (-650 3400);
DISPLAY INVISIBLE (-650 3400);
FORCEPROP 2 LAST SEC_TYPE 0402V
J 0
(-650 3450);
DISPLAY 1.021277 (-650 3450);
PAINT ORANGE (-650 3450);
DISPLAY INVISIBLE (-650 3450);
FORCEPROP 2 LAST SEC 1
J 0
(-650 3450);
DISPLAY 0.680851 (-650 3450);
PAINT MONO (-650 3450);
DISPLAY INVISIBLE (-650 3450);
FORCEPROP 1 LAST PATH I86
J 2
(-650 3400);
DISPLAY 0.978723 (-650 3400);
PAINT WHITE (-650 3400);
DISPLAY INVISIBLE (-650 3400);
FORCEPROP 2 LAST ROOM P0V95_MCP_CPU0
J 2
(-650 3400);
DISPLAY 1.659574 (-650 3400);
PAINT WHITE (-650 3400);
DISPLAY INVISIBLE (-650 3400);
FORCEADD CAP_A..1
R 2
(-475 1075);
FORCEPROP 1 LAST LOCATION C4T2
J 2
(-525 1175);
DISPLAY 0.617021 (-525 1175);
PAINT AQUA (-525 1175);
FORCEPROP 1 LAST PART_NUMBER D97712-004
J 2
(-525 925);
DISPLAY 0.617021 (-525 925);
PAINT BLUE (-525 925);
FORCEPROP 1 LAST VALUE 1.0UF
J 2
(-525 1125);
DISPLAY 0.617021 (-525 1125);
PAINT SKYBLUE (-525 1125);
FORCEPROP 1 LAST TOLERANCE 10%
J 2
(-525 1025);
DISPLAY 0.617021 (-525 1025);
PAINT SKYBLUE (-525 1025);
FORCEPROP 1 LAST PACK_TYPE 0402V
J 2
(-525 875);
DISPLAY 0.617021 (-525 875);
PAINT SKYBLUE (-525 875);
FORCEPROP 1 LAST VOLTAGE 6.3V
J 2
(-525 1075);
DISPLAY 0.617021 (-525 1075);
PAINT SKYBLUE (-525 1075);
FORCEPROP 1 LAST MATERIAL X6S
J 2
(-525 975);
DISPLAY 0.617021 (-525 975);
PAINT SKYBLUE (-525 975);
FORCEPROP 1 LASTPIN (-475 1175) $PN 1
J 2
(-485 1155);
DISPLAY 0.617021 (-485 1155);
PAINT ORANGE (-485 1155);
FORCEPROP 1 LASTPIN (-475 975) $PN 2
J 2
(-485 955);
DISPLAY 0.617021 (-485 955);
PAINT ORANGE (-485 955);
FORCEPROP 2 LAST CDS_LOCATION C4T2
J 2
(-525 1175);
DISPLAY 0.617021 (-525 1175);
PAINT AQUA (-525 1175);
DISPLAY INVISIBLE (-525 1175);
FORCEPROP 2 LAST CDS_LIB dev_discrete
J 0
(-475 1075);
PAINT ORANGE (-475 1075);
DISPLAY INVISIBLE (-475 1075);
FORCEPROP 2 LAST CDS_SEC 1
J 0
(-525 1225);
PAINT ORANGE (-525 1225);
DISPLAY INVISIBLE (-525 1225);
FORCEPROP 2 LAST SEC_TYPE 0402V
J 0
(-525 1275);
DISPLAY 1.021277 (-525 1275);
PAINT ORANGE (-525 1275);
DISPLAY INVISIBLE (-525 1275);
FORCEPROP 2 LAST SEC 1
J 0
(-525 1275);
DISPLAY 0.680851 (-525 1275);
PAINT MONO (-525 1275);
DISPLAY INVISIBLE (-525 1275);
FORCEPROP 1 LAST PATH I9
J 2
(-525 1225);
DISPLAY 0.978723 (-525 1225);
PAINT WHITE (-525 1225);
DISPLAY INVISIBLE (-525 1225);
FORCEPROP 2 LAST ROOM P1V8_MCP_CPU0
J 2
(-525 1225);
DISPLAY 1.659574 (-525 1225);
PAINT WHITE (-525 1225);
DISPLAY INVISIBLE (-525 1225);
FORCEADD GND..1
(-1025 2900);
FORCEPROP 3 LASTPIN (-1025 2950) SIG_NAME GND\g
J 0
(-1015 2960);
DISPLAY 0.659574 (-1015 2960);
PAINT MONO (-1015 2960);
DISPLAY INVISIBLE (-1015 2960);
FORCEPROP 1 LAST VOLTAGE 0.0V
J 0
(-1070 2857);
DISPLAY 0.340426 (-1070 2857);
PAINT SKYBLUE (-1070 2857);
DISPLAY INVISIBLE (-1070 2857);
FORCEPROP 1 LAST SIZE 1B
J 0
(-950 2850);
DISPLAY 1.404255 (-950 2850);
PAINT AQUA (-950 2850);
DISPLAY INVISIBLE (-950 2850);
FORCEPROP 2 LAST CDS_LIB mstr_symbols
J 0
(-1025 2900);
PAINT ORANGE (-1025 2900);
DISPLAY INVISIBLE (-1025 2900);
FORCEPROP 1 LAST BODY_TYPE PLUMBING
J 0
(-1070 2857);
DISPLAY 0.340426 (-1070 2857);
PAINT GREEN (-1070 2857);
DISPLAY INVISIBLE (-1070 2857);
FORCEPROP 1 LAST PATH I92
J 0
(-950 2900);
DISPLAY 0.872340 (-950 2900);
PAINT AQUA (-950 2900);
DISPLAY INVISIBLE (-950 2900);
FORCEPROP 1 LAST HDL_POWER GND
J 0
(-1025 3050);
PAINT GREEN (-1025 3050);
DISPLAY INVISIBLE (-1025 3050);
FORCEADD VCC_CORE..1
(-1025 3650);
FORCEPROP 3 LASTPIN (-1025 3600) SIG_NAME PVCCIOMCP_CPU0\g
J 0
(-1015 3610);
DISPLAY 0.659574 (-1015 3610);
PAINT MONO (-1015 3610);
DISPLAY INVISIBLE (-1015 3610);
FORCEPROP 1 LAST HDL_POWER PVCCIOMCP_CPU0
J 1
(-1025 3700);
DISPLAY 0.617021 (-1025 3700);
PAINT GREEN (-1025 3700);
FORCEPROP 2 LAST CDS_LIB mstr_symbols
J 0
(-1025 3650);
PAINT ORANGE (-1025 3650);
DISPLAY INVISIBLE (-1025 3650);
FORCEPROP 1 LAST PATH I95
J 0
(-975 3675);
DISPLAY 0.872340 (-975 3675);
PAINT AQUA (-975 3675);
DISPLAY INVISIBLE (-975 3675);
FORCEADD CAP_A..1
R 2
(-1025 3250);
FORCEPROP 1 LAST LOCATION C3M46
J 2
(-1075 3350);
DISPLAY 0.617021 (-1075 3350);
PAINT AQUA (-1075 3350);
FORCEPROP 1 LAST PART_NUMBER D97712-004
J 2
(-1075 3100);
DISPLAY 0.617021 (-1075 3100);
PAINT BLUE (-1075 3100);
FORCEPROP 1 LAST VALUE 1.0UF
J 2
(-1075 3300);
DISPLAY 0.617021 (-1075 3300);
PAINT SKYBLUE (-1075 3300);
FORCEPROP 1 LAST TOLERANCE 10%
J 2
(-1075 3200);
DISPLAY 0.617021 (-1075 3200);
PAINT SKYBLUE (-1075 3200);
FORCEPROP 1 LAST PACK_TYPE 0402V
J 2
(-1075 3050);
DISPLAY 0.617021 (-1075 3050);
PAINT SKYBLUE (-1075 3050);
FORCEPROP 1 LAST VOLTAGE 6.3V
J 2
(-1075 3250);
DISPLAY 0.617021 (-1075 3250);
PAINT SKYBLUE (-1075 3250);
FORCEPROP 1 LAST MATERIAL X6S
J 2
(-1075 3150);
DISPLAY 0.617021 (-1075 3150);
PAINT SKYBLUE (-1075 3150);
FORCEPROP 1 LASTPIN (-1025 3350) $PN 1
J 2
(-1035 3330);
DISPLAY 0.617021 (-1035 3330);
PAINT ORANGE (-1035 3330);
FORCEPROP 1 LASTPIN (-1025 3150) $PN 2
J 2
(-1035 3130);
DISPLAY 0.617021 (-1035 3130);
PAINT ORANGE (-1035 3130);
FORCEPROP 2 LAST CDS_LIB dev_discrete
J 0
(-1025 3250);
PAINT ORANGE (-1025 3250);
DISPLAY INVISIBLE (-1025 3250);
FORCEPROP 2 LAST CDS_SEC 1
J 0
(-1075 3400);
PAINT ORANGE (-1075 3400);
DISPLAY INVISIBLE (-1075 3400);
FORCEPROP 2 LAST SEC_TYPE 0402V
J 0
(-1075 3450);
DISPLAY 1.021277 (-1075 3450);
PAINT ORANGE (-1075 3450);
DISPLAY INVISIBLE (-1075 3450);
FORCEPROP 2 LAST SEC 1
J 0
(-1075 3450);
DISPLAY 0.680851 (-1075 3450);
PAINT MONO (-1075 3450);
DISPLAY INVISIBLE (-1075 3450);
FORCEPROP 1 LAST PATH I99
J 2
(-1075 3400);
DISPLAY 0.978723 (-1075 3400);
PAINT WHITE (-1075 3400);
DISPLAY INVISIBLE (-1075 3400);
FORCEPROP 2 LAST ROOM P0V95_MCP_CPU0
J 2
(-1075 3400);
DISPLAY 1.659574 (-1075 3400);
PAINT WHITE (-1075 3400);
DISPLAY INVISIBLE (-1075 3400);
FORCEADD DESIGN_NOTE..1
(-7350 50);
PAINT PURPLE (-7350 50);
FORCEPROP 0 LAST L1 SVID ADDRESS: VCCMCP: 0X03, VCCIOMCP 0X04, P1V8MCP 0X05
J 0
(-7550 -75);
PAINT VIOLET (-7550 -75);
FORCEPROP 2 LAST BOM_COST SM_CONTROLLER
J 0
(-7550 0);
PAINT MONO (-7550 0);
DISPLAY INVISIBLE (-7550 0);
FORCEPROP 2 LAST CDS_LIB mstr_symbols
J 0
(-7350 50);
PAINT MONO (-7350 50);
DISPLAY INVISIBLE (-7350 50);
FORCEPROP 1 LAST COMMENT_BODY TRUE
J 0
(-7325 150);
DISPLAY 1.319149 (-7325 150);
PAINT GREEN (-7325 150);
DISPLAY INVISIBLE (-7325 150);
FORCEPROP 2 LAST ROOM PVCCIN_CPU0_VR
J 0
(-7550 0);
PAINT MONO (-7550 0);
DISPLAY INVISIBLE (-7550 0);
FORCEADD INTEL_CORP_BPAGE..1
(-400 -625);
FORCEPROP 1 LAST CDS_CON_LAST_MODIFIED Tue Dec 01 11:52:18 2015
J 0
(-1825 -300);
DISPLAY 1.361702 (-1825 -300);
PAINT GREEN (-1825 -300);
DISPLAY INVISIBLE (-1825 -300);
FORCEPROP 1 LAST CUSTOM_TXT_CDS <CURRENT_DESIGN_SHEET> OF <TOTAL_DESIGN_SHEETS>
J 0
(-900 -600);
PAINT GREEN (-900 -600);
FORCEPROP 2 LAST CUSTOM_TXT_CDS <XR_PAGE_TITLE>
J 0
(-8290 4625);
DISPLAY 0.638298 (-8290 4625);
PAINT PINK (-8290 4625);
DISPLAY INVISIBLE (-8290 4625);
FORCEPROP 2 LAST CUSTOM_TXT_CDS <CON_LAST_MODIFIED>
J 0
(-2325 -275);
DISPLAY 1.361702 (-2325 -275);
PAINT GREEN (-2325 -275);
FORCEPROP 1 LAST SCH_ADDRESS3 Santa Clara, CA 95052-8119
J 0
(-4375 -600);
DISPLAY 0.617021 (-4375 -600);
PAINT GREEN (-4375 -600);
FORCEPROP 1 LAST SCH_ADDRESS2 P.O. BOX 58119
J 0
(-4375 -550);
DISPLAY 0.617021 (-4375 -550);
PAINT GREEN (-4375 -550);
FORCEPROP 1 LAST SCH_ADDRESS1 2200 Mission College Blvd.
J 0
(-4375 -500);
DISPLAY 0.617021 (-4375 -500);
PAINT GREEN (-4375 -500);
FORCEPROP 1 LAST SCH_TITLE MCP CPU0 VRM
J 0
(-8350 -575);
DISPLAY 1.212766 (-8350 -575);
PAINT ORANGE (-8350 -575);
FORCEPROP 1 LAST SCH_NUMBER H4694802
J 0
(-1700 -475);
DISPLAY 1.212766 (-1700 -475);
PAINT YELLOW (-1700 -475);
FORCEPROP 1 LAST SCH_DEPT BESD
J 1
(-4850 -525);
DISPLAY 1.212766 (-4850 -525);
PAINT YELLOW (-4850 -525);
FORCEPROP 1 LAST SCH_REV 2.420
J 0
(-650 -475);
DISPLAY 0.978723 (-650 -475);
PAINT YELLOW (-650 -475);
FORCEPROP 2 LAST PAGE_BORDER TRUE
J 0
(-8290 4625);
DISPLAY 0.851064 (-8290 4625);
PAINT PINK (-8290 4625);
DISPLAY INVISIBLE (-8290 4625);
FORCEPROP 2 LAST CDS_LIB mstr_symbols
J 0
(-400 -625);
DISPLAY 1.361702 (-400 -625);
PAINT ORANGE (-400 -625);
DISPLAY INVISIBLE (-400 -625);
FORCEPROP 1 LAST COMMENT_BODY TRUE
J 0
(-388 -613);
DISPLAY 0.617021 (-388 -613);
PAINT GREEN (-388 -613);
DISPLAY INVISIBLE (-388 -613);
FORCEPROP 2 LAST CDS_XR_PAGE_TITLE CR-194 : @BASEBOARD_FAB2_LIB.BASEBOARD_FAB2(SCH_1):PAGE194
J 0
(-8290 4625);
DISPLAY 0.638298 (-8290 4625);
PAINT PINK (-8290 4625);
DISPLAY INVISIBLE (-8290 4625);
WIRE 16 -1 (-1450 3050)(-1450 2925);
WIRE 16 -1 (-1450 3375)(-1450 3250);
WIRE 16 -1 (-6950 3675)(-7375 3675);
WIRE 16 -1 (-7375 3325)(-7375 3675);
WIRE 16 -1 (-6950 3325)(-7375 3325);
WIRE 16 -1 (-7375 3275)(-7375 3325);
WIRE 16 -1 (-6950 3275)(-7375 3275);
WIRE 16 -1 (-7375 3225)(-7375 3275);
WIRE 16 -1 (-6950 3225)(-7375 3225);
WIRE 16 -1 (-7375 3225)(-7375 3175);
WIRE 16 -1 (-6950 3175)(-7375 3175);
WIRE 16 -1 (-7375 3175)(-7375 2975);
WIRE 16 -1 (-6950 2975)(-7375 2975);
WIRE 16 -1 (-7375 2975)(-7375 2925);
WIRE 16 -1 (-6950 2925)(-7375 2925);
WIRE 16 -1 (-7375 2925)(-7375 2875);
WIRE 16 -1 (-6950 2875)(-7375 2875);
WIRE 16 -1 (-7375 2875)(-7375 2825);
WIRE 16 -1 (-6950 2825)(-7375 2825);
WIRE 16 -1 (-7375 2825)(-7375 2625);
WIRE 16 -1 (-6950 2625)(-7375 2625);
WIRE 16 -1 (-7375 2625)(-7375 2575);
WIRE 16 -1 (-6950 2575)(-7375 2575);
WIRE 16 -1 (-7375 2575)(-7375 2525);
WIRE 16 -1 (-6950 2525)(-7375 2525);
WIRE 16 -1 (-7375 2525)(-7375 2475);
WIRE 16 -1 (-6950 2475)(-7375 2475);
WIRE 16 -1 (-7375 2475)(-7375 2275);
WIRE 16 -1 (-6950 2275)(-7375 2275);
WIRE 16 -1 (-7375 2275)(-7375 2225);
WIRE 16 -1 (-6950 2225)(-7375 2225);
WIRE 16 -1 (-7375 2225)(-7375 2175);
WIRE 16 -1 (-6950 2175)(-7375 2175);
WIRE 16 -1 (-7375 2175)(-7375 2125);
WIRE 16 -1 (-6950 2125)(-7375 2125);
WIRE 16 -1 (-7375 2125)(-7375 1925);
WIRE 16 -1 (-6950 1925)(-7375 1925);
WIRE 16 -1 (-7375 1925)(-7375 1875);
WIRE 16 -1 (-6950 1875)(-7375 1875);
WIRE 16 -1 (-7375 1875)(-7375 1825);
WIRE 16 -1 (-6950 1825)(-7375 1825);
WIRE 16 -1 (-7375 1825)(-7375 1775);
WIRE 16 -1 (-6950 1775)(-7375 1775);
WIRE 16 -1 (-7375 1775)(-7375 1575);
WIRE 16 -1 (-6950 1575)(-7375 1575);
WIRE 16 -1 (-7375 1575)(-7375 1525);
WIRE 16 -1 (-6950 1525)(-7375 1525);
WIRE 16 -1 (-7375 1475)(-7375 1525);
WIRE 16 -1 (-6950 1475)(-7375 1475);
WIRE 16 -1 (-7375 1425)(-7375 1475);
WIRE 16 -1 (-6950 1425)(-7375 1425);
WIRE 16 -1 (-7375 1275)(-7375 1425);
WIRE 16 -1 (-6950 475)(-7075 475);
WIRE 16 -1 (-7075 525)(-7075 475);
WIRE 16 -1 (-6950 525)(-7075 525);
WIRE 16 -1 (-7075 575)(-7075 525);
WIRE 16 -1 (-6950 575)(-7075 575);
WIRE 16 -1 (-7075 625)(-7075 575);
WIRE 16 -1 (-6950 625)(-7075 625);
WIRE 16 -1 (-7075 725)(-7075 625);
WIRE 16 -1 (-6950 725)(-7075 725);
WIRE 16 -1 (-7075 775)(-7075 725);
WIRE 16 -1 (-6950 775)(-7075 775);
WIRE 16 -1 (-7075 800)(-7075 775);
WIRE 16 -1 (-7075 825)(-7075 800);
WIRE 16 -1 (-7225 800)(-7075 800);
WIRE 16 -1 (-7225 725)(-7225 800);
WIRE 16 -1 (-7075 875)(-7075 825);
WIRE 16 -1 (-6950 825)(-7075 825);
WIRE 16 -1 (-7075 875)(-7075 925);
WIRE 16 -1 (-6950 875)(-7075 875);
WIRE 16 -1 (-7075 925)(-7075 975);
WIRE 16 -1 (-6950 925)(-7075 925);
WIRE 16 -1 (-7075 975)(-7075 1175);
WIRE 16 -1 (-6950 975)(-7075 975);
WIRE 16 -1 (-7075 1175)(-7075 1225);
WIRE 16 -1 (-6950 1175)(-7075 1175);
WIRE 16 -1 (-6950 1225)(-7075 1225);
WIRE 16 -1 (-7175 1275)(-6950 1275);
WIRE 16 -1 (-7175 1325)(-7175 1275);
WIRE 16 -1 (-7175 1325)(-6950 1325);
WIRE 16 -1 (-7175 1625)(-7175 1325);
WIRE 16 -1 (-6950 1625)(-7175 1625);
WIRE 16 -1 (-7175 1625)(-7175 1675);
WIRE 16 -1 (-6950 1675)(-7175 1675);
WIRE 16 -1 (-7175 1675)(-7175 1975);
WIRE 16 -1 (-6950 1975)(-7175 1975);
WIRE 16 -1 (-7175 1975)(-7175 2025);
WIRE 16 -1 (-6950 2025)(-7175 2025);
WIRE 16 -1 (-7175 2025)(-7175 2325);
WIRE 16 -1 (-6950 2325)(-7175 2325);
WIRE 16 -1 (-7175 2325)(-7175 2375);
WIRE 16 -1 (-6950 2375)(-7175 2375);
WIRE 16 -1 (-7175 2375)(-7175 2675);
WIRE 16 -1 (-6950 2675)(-7175 2675);
WIRE 16 -1 (-7175 2675)(-7175 2725);
WIRE 16 -1 (-6950 2725)(-7175 2725);
WIRE 16 -1 (-7175 2725)(-7175 3025);
WIRE 16 -1 (-6950 3025)(-7175 3025);
WIRE 16 -1 (-7175 3025)(-7175 3075);
WIRE 16 -1 (-6950 3075)(-7175 3075);
WIRE 16 -1 (-7175 3075)(-7175 3375);
WIRE 16 -1 (-6950 3375)(-7175 3375);
WIRE 16 -1 (-7175 3375)(-7175 3425);
WIRE 16 -1 (-6950 3425)(-7175 3425);
WIRE 16 -1 (-7175 3425)(-7175 3725);
WIRE 16 -1 (-6950 3725)(-7175 3725);
WIRE 16 -1 (-7175 3725)(-7175 3775);
WIRE 16 -1 (-6950 3775)(-7175 3775);
WIRE 16 -1 (-7175 3775)(-7175 4025);
WIRE 16 -1 (-6150 3675)(-5725 3675);
WIRE 16 -1 (-5725 3675)(-5725 3725);
WIRE 16 -1 (-6150 3725)(-5725 3725);
WIRE 16 -1 (-5725 3725)(-5725 3775);
WIRE 16 -1 (-5725 3850)(-5725 3775);
WIRE 16 -1 (-5725 3775)(-6150 3775);
WIRE 16 -1 (-6150 2975)(-5775 2975);
WIRE 16 -1 (-5775 2975)(-5775 3025);
WIRE 16 -1 (-6150 3025)(-5775 3025);
WIRE 16 -1 (-5775 3025)(-5775 3075);
WIRE 16 -1 (-6150 3075)(-5775 3075);
WIRE 16 -1 (-5775 3075)(-5775 3150);
WIRE 16 -1 (-6150 3625)(-6025 3625);
WIRE 16 -1 (-6025 3625)(-6025 3575);
WIRE 16 -1 (-6150 3575)(-6025 3575);
WIRE 16 -1 (-6025 3575)(-6025 3525);
WIRE 16 -1 (-6150 3525)(-6025 3525);
WIRE 16 -1 (-6025 3525)(-6025 3425);
WIRE 16 -1 (-6150 3425)(-6025 3425);
WIRE 16 -1 (-6025 3425)(-6025 3375);
WIRE 16 -1 (-6150 3375)(-6025 3375);
WIRE 16 -1 (-6025 3375)(-6025 3325);
WIRE 16 -1 (-6150 3325)(-6025 3325);
WIRE 16 -1 (-6025 3325)(-6025 3275);
WIRE 16 -1 (-6150 3275)(-6025 3275);
WIRE 16 -1 (-6025 3275)(-6025 3225);
WIRE 16 -1 (-6150 3225)(-6025 3225);
WIRE 16 -1 (-6025 3225)(-6025 3175);
WIRE 16 -1 (-6150 3175)(-6025 3175);
WIRE 16 -1 (-6025 2925)(-6025 3175);
WIRE 16 -1 (-6150 2925)(-6025 2925);
WIRE 16 -1 (-6025 2925)(-6025 2875);
WIRE 16 -1 (-6150 2875)(-6025 2875);
WIRE 16 -1 (-6025 2875)(-6025 2825);
WIRE 16 -1 (-6150 2825)(-6025 2825);
WIRE 16 -1 (-6025 2825)(-6025 2725);
WIRE 16 -1 (-6150 2725)(-6025 2725);
WIRE 16 -1 (-6025 2725)(-6025 2675);
WIRE 16 -1 (-6150 2675)(-6025 2675);
WIRE 16 -1 (-6025 2675)(-6025 2625);
WIRE 16 -1 (-6150 2625)(-6025 2625);
WIRE 16 -1 (-6025 2625)(-6025 2575);
WIRE 16 -1 (-6150 2575)(-6025 2575);
WIRE 16 -1 (-6025 2525)(-6025 2575);
WIRE 16 -1 (-6150 2525)(-6025 2525);
WIRE 16 -1 (-6025 2475)(-6025 2525);
WIRE 16 -1 (-6150 2475)(-6025 2475);
WIRE 16 -1 (-6025 2275)(-6025 2475);
WIRE 16 -1 (-6150 2275)(-6025 2275);
WIRE 16 -1 (-6025 1925)(-6025 2275);
WIRE 16 -1 (-6150 1925)(-6025 1925);
WIRE 16 -1 (-6025 1925)(-6025 1675);
WIRE 16 -1 (-6150 1675)(-6025 1675);
WIRE 16 -1 (-6025 1675)(-5350 1675);
WIRE 16 -1 (-5350 1675)(-5350 1625);
WIRE 16 -1 (-6150 1625)(-5350 1625);
WIRE 16 -1 (-5350 1625)(-5350 1575);
WIRE 16 -1 (-3550 3000)(-3725 3000);
WIRE 16 -1 (-3725 3000)(-3725 3050);
WIRE 16 -1 (-3550 3050)(-3725 3050);
WIRE 16 -1 (-3725 3050)(-3725 3100);
WIRE 16 -1 (-3550 3100)(-3725 3100);
WIRE 16 -1 (-3725 3100)(-3725 3350);
WIRE 16 -1 (-3550 3350)(-3725 3350);
WIRE 16 -1 (-3725 3350)(-3725 3400);
WIRE 16 -1 (-3550 3400)(-3725 3400);
WIRE 16 -1 (-3725 3400)(-3725 3450);
WIRE 16 -1 (-3550 3450)(-3725 3450);
WIRE 16 -1 (-3725 3450)(-3725 3700);
WIRE 16 -1 (-3550 3700)(-3725 3700);
WIRE 16 -1 (-3725 3700)(-3725 3750);
WIRE 16 -1 (-3550 3750)(-3725 3750);
WIRE 16 -1 (-3725 3750)(-3725 3800);
WIRE 16 -1 (-3550 3800)(-3725 3800);
WIRE 16 -1 (-3725 3800)(-3900 3800);
WIRE 16 -1 (-3900 3800)(-3900 3875);
WIRE 16 -1 (-3550 3200)(-3900 3200);
WIRE 16 -1 (-3900 3250)(-3900 3200);
WIRE 16 -1 (-3550 3250)(-3900 3250);
WIRE 16 -1 (-3900 3250)(-3900 3550);
WIRE 16 -1 (-3550 3550)(-3900 3550);
WIRE 16 -1 (-3900 3600)(-3900 3550);
WIRE 16 -1 (-3550 3600)(-3900 3600);
WIRE 16 -1 (-3900 3750)(-3900 3600);
WIRE 16 -1 (-3900 3750)(-4175 3750);
WIRE 16 -1 (-4175 4000)(-4175 3750);
WIRE 16 -1 (-1750 1175)(-1750 1275);
WIRE 16 -1 (-1750 1275)(-1450 1275);
WIRE 16 -1 (-1450 1300)(-1450 1275);
WIRE 16 -1 (-1450 1275)(-1450 1200);
WIRE 16 -1 (-475 1300)(-475 1175);
WIRE 16 -1 (-900 1300)(-475 1300);
WIRE 16 -1 (-900 1175)(-900 1300);
WIRE 16 -1 (-900 1300)(-900 1425);
WIRE 16 -1 (-6150 725)(-5450 725);
WIRE 16 -1 (-5450 725)(-5450 775);
WIRE 16 -1 (-6150 775)(-5450 775);
WIRE 16 -1 (-5450 775)(-5450 825);
WIRE 16 -1 (-6150 825)(-5450 825);
WIRE 16 -1 (-5450 825)(-5450 875);
WIRE 16 -1 (-6150 875)(-5450 875);
WIRE 16 -1 (-5450 875)(-5450 1075);
WIRE 16 -1 (-6150 1075)(-5450 1075);
WIRE 16 -1 (-5450 1075)(-5450 1125);
WIRE 16 -1 (-6150 1125)(-5450 1125);
WIRE 16 -1 (-5450 1125)(-5450 1175);
WIRE 16 -1 (-6150 1175)(-5450 1175);
WIRE 16 -1 (-5450 1175)(-5450 1225);
WIRE 16 -1 (-6150 1225)(-5450 1225);
WIRE 16 -1 (-5450 1425)(-5450 1225);
WIRE 16 -1 (-6150 1425)(-5450 1425);
WIRE 16 -1 (-5450 1425)(-5450 1475);
WIRE 16 -1 (-6150 1475)(-5450 1475);
WIRE 16 -1 (-5450 1475)(-5450 1525);
WIRE 16 -1 (-6150 1525)(-5450 1525);
WIRE 16 -1 (-5450 1525)(-5450 1575);
WIRE 16 -1 (-6150 1575)(-5450 1575);
WIRE 16 -1 (-5450 1575)(-5450 1775);
WIRE 16 -1 (-6150 1775)(-5450 1775);
WIRE 16 -1 (-5450 1775)(-5450 1825);
WIRE 16 -1 (-6150 1825)(-5450 1825);
WIRE 16 -1 (-5450 1825)(-5450 1875);
WIRE 16 -1 (-6150 1875)(-5450 1875);
WIRE 16 -1 (-5450 1875)(-5450 2125);
WIRE 16 -1 (-6150 2125)(-5450 2125);
WIRE 16 -1 (-5450 2125)(-5450 2175);
WIRE 16 -1 (-6150 2175)(-5450 2175);
WIRE 16 -1 (-5450 2175)(-5450 2225);
WIRE 16 -1 (-6150 2225)(-5450 2225);
WIRE 16 -1 (-5450 2225)(-5450 2525);
WIRE 16 -1 (-475 975)(-475 875);
WIRE 16 -1 (-475 875)(-900 875);
WIRE 16 -1 (-900 975)(-900 875);
WIRE 16 -1 (-900 875)(-900 825);
WIRE 16 -1 (-7425 3525)(-6950 3525);
WIRE 16 -1 (-7425 3850)(-7425 3525);
WIRE 16 -1 (-8175 25)(-8175 -125);
WIRE 16 -1 (-8175 -125)(-7975 -125);
WIRE 16 -1 (-7825 -125)(-7975 -125);
WIRE 16 -1 (-7975 -125)(-7975 -175);
WIRE 16 -1 (-7825 0)(-7825 -125);
WIRE 16 -1 (-7525 3625)(-6950 3625);
WIRE 16 -1 (-7525 3750)(-7525 3625);
WIRE 16 -1 (-1750 975)(-1750 850);
WIRE 16 -1 (-1750 850)(-1450 850);
WIRE 16 -1 (-1450 1000)(-1450 850);
WIRE 16 -1 (-1450 850)(-1450 800);
WIRE 16 -1 (-850 2375)(-850 2475);
WIRE 16 -1 (-850 2475)(-1275 2475);
FORCEPROP 0 LAST VOLTAGE 1.2V
J 0
(-1050 2525);
DISPLAY 1.021277 (-1050 2525);
PAINT SKYBLUE (-1050 2525);
DISPLAY INVISIBLE (-1050 2525);
WIRE 16 -1 (-1275 2375)(-1275 2475);
WIRE 16 -1 (-1275 2475)(-1275 2550);
WIRE 16 -1 (-850 2175)(-850 2050);
WIRE 16 -1 (-850 2050)(-1275 2050);
WIRE 16 -1 (-1275 2050)(-1275 2175);
WIRE 16 -1 (-1275 1925)(-1275 2050);
WIRE 16 -1 (-3550 2950)(-3975 2950);
WIRE 16 -1 (-3975 2950)(-3975 2900);
WIRE 16 -1 (-3550 2900)(-3975 2900);
WIRE 16 -1 (-3975 2900)(-3975 2850);
WIRE 16 -1 (-3550 2850)(-3975 2850);
WIRE 16 -1 (-3975 2850)(-3975 2600);
WIRE 16 -1 (-3550 2600)(-3975 2600);
WIRE 16 -1 (-3975 2600)(-3975 2550);
WIRE 16 -1 (-3550 2550)(-3975 2550);
WIRE 16 -1 (-3975 2550)(-3975 2500);
WIRE 16 -1 (-3550 2500)(-3975 2500);
WIRE 16 -1 (-3975 2500)(-3975 2250);
WIRE 16 -1 (-3550 2250)(-3975 2250);
WIRE 16 -1 (-3975 1900)(-3975 2250);
WIRE 16 -1 (-3550 1900)(-3975 1900);
WIRE 16 -1 (-3975 1900)(-3975 1850);
WIRE 16 -1 (-3550 1850)(-3975 1850);
WIRE 16 -1 (-3975 1850)(-3975 1800);
WIRE 16 -1 (-3550 1800)(-3975 1800);
WIRE 16 -1 (-3975 1800)(-3975 1550);
WIRE 16 -1 (-3550 1550)(-3975 1550);
WIRE 16 -1 (-3975 1550)(-3975 1500);
WIRE 16 -1 (-3550 1500)(-3975 1500);
WIRE 16 -1 (-3975 1500)(-3975 1450);
WIRE 16 -1 (-3550 1450)(-3975 1450);
WIRE 16 -1 (-3975 1450)(-3975 1200);
WIRE 16 -1 (-3550 1200)(-3975 1200);
WIRE 16 -1 (-3975 1200)(-3975 1150);
WIRE 16 -1 (-3550 1150)(-3975 1150);
WIRE 16 -1 (-3975 1150)(-3975 1100);
WIRE 16 -1 (-3550 1100)(-3975 1100);
WIRE 16 -1 (-3975 1100)(-3975 850);
WIRE 16 -1 (-3550 850)(-3975 850);
WIRE 16 -1 (-3975 850)(-3975 800);
WIRE 16 -1 (-3550 800)(-3975 800);
WIRE 16 -1 (-3975 800)(-3975 750);
WIRE 16 -1 (-3550 750)(-3975 750);
WIRE 16 -1 (-3975 750)(-3975 500);
WIRE 16 -1 (-3550 500)(-3975 500);
WIRE 16 -1 (-3975 500)(-3975 450);
WIRE 16 -1 (-3550 450)(-3975 450);
WIRE 16 -1 (-3975 450)(-3975 400);
WIRE 16 -1 (-3550 400)(-3975 400);
WIRE 16 -1 (-3975 400)(-3975 275);
WIRE 16 -1 (-2750 3650)(-2150 3650);
WIRE 16 -1 (-2150 3650)(-2150 3600);
WIRE 16 -1 (-2750 3600)(-2150 3600);
WIRE 16 -1 (-2150 3600)(-2150 3550);
WIRE 16 -1 (-2750 3550)(-2150 3550);
WIRE 16 -1 (-2150 3550)(-2150 3300);
WIRE 16 -1 (-2750 3300)(-2150 3300);
WIRE 16 -1 (-2150 3300)(-2150 3250);
WIRE 16 -1 (-2750 3250)(-2150 3250);
WIRE 16 -1 (-2150 3250)(-2150 3200);
WIRE 16 -1 (-2750 3200)(-2150 3200);
WIRE 16 -1 (-2150 3200)(-2150 2950);
WIRE 16 -1 (-2750 2950)(-2150 2950);
WIRE 16 -1 (-2150 2950)(-2150 2900);
WIRE 16 -1 (-2750 2900)(-2150 2900);
WIRE 16 -1 (-2150 2900)(-2150 2850);
WIRE 16 -1 (-2750 2850)(-2150 2850);
WIRE 16 -1 (-2150 2850)(-2150 2600);
WIRE 16 -1 (-2750 2600)(-2150 2600);
WIRE 16 -1 (-2150 2600)(-2150 2550);
WIRE 16 -1 (-2750 2550)(-2150 2550);
WIRE 16 -1 (-2150 2550)(-2150 2500);
WIRE 16 -1 (-2750 2500)(-2150 2500);
WIRE 16 -1 (-2150 2500)(-2150 2250);
WIRE 16 -1 (-2750 2250)(-2150 2250);
WIRE 16 -1 (-2150 2250)(-2150 2200);
WIRE 16 -1 (-2750 2200)(-2150 2200);
WIRE 16 -1 (-2150 2200)(-2150 2150);
WIRE 16 -1 (-2750 2150)(-2150 2150);
WIRE 16 -1 (-2150 2150)(-2150 1900);
WIRE 16 -1 (-2750 1900)(-2150 1900);
WIRE 16 -1 (-2150 1900)(-2150 1850);
WIRE 16 -1 (-2750 1850)(-2150 1850);
WIRE 16 -1 (-2150 1850)(-2150 1800);
WIRE 16 -1 (-2750 1800)(-2150 1800);
WIRE 16 -1 (-2150 1800)(-2150 1550);
WIRE 16 -1 (-2750 1550)(-2150 1550);
WIRE 16 -1 (-2150 1550)(-2150 1500);
WIRE 16 -1 (-2750 1500)(-2150 1500);
WIRE 16 -1 (-2150 1500)(-2150 1450);
WIRE 16 -1 (-2750 1450)(-2150 1450);
WIRE 16 -1 (-2150 1200)(-2150 1450);
WIRE 16 -1 (-2750 1200)(-2150 1200);
WIRE 16 -1 (-2150 1200)(-2150 1150);
WIRE 16 -1 (-2750 1150)(-2150 1150);
WIRE 16 -1 (-2150 1150)(-2150 1100);
WIRE 16 -1 (-2750 1100)(-2150 1100);
WIRE 16 -1 (-2150 1100)(-2150 1000);
WIRE 16 -1 (-2750 1000)(-2150 1000);
WIRE 16 -1 (-2150 1000)(-2150 950);
WIRE 16 -1 (-2750 950)(-2150 950);
WIRE 16 -1 (-2150 950)(-2150 900);
WIRE 16 -1 (-2750 900)(-2150 900);
WIRE 16 -1 (-2150 900)(-2150 850);
WIRE 16 -1 (-2750 850)(-2150 850);
WIRE 16 -1 (-2150 850)(-2150 800);
WIRE 16 -1 (-2750 800)(-2150 800);
WIRE 16 -1 (-2150 800)(-2150 750);
WIRE 16 -1 (-2750 750)(-2150 750);
WIRE 16 -1 (-2150 750)(-2150 650);
WIRE 16 -1 (-2750 650)(-2150 650);
WIRE 16 -1 (-2150 650)(-2150 600);
WIRE 16 -1 (-2750 600)(-2150 600);
WIRE 16 -1 (-2150 600)(-2150 550);
WIRE 16 -1 (-2750 550)(-2150 550);
WIRE 16 -1 (-2150 550)(-2150 500);
WIRE 16 -1 (-2750 500)(-2150 500);
WIRE 16 -1 (-2150 500)(-2150 450);
WIRE 16 -1 (-2750 450)(-2150 450);
WIRE 16 -1 (-2150 450)(-2150 400);
WIRE 16 -1 (-2750 400)(-2150 400);
WIRE 16 -1 (-2150 400)(-2150 250);
WIRE 16 -1 (-3550 550)(-3725 550);
WIRE 16 -1 (-3725 550)(-3725 600);
WIRE 16 -1 (-3550 600)(-3725 600);
WIRE 16 -1 (-3725 600)(-3725 650);
WIRE 16 -1 (-3550 650)(-3725 650);
WIRE 16 -1 (-3725 650)(-3725 900);
WIRE 16 -1 (-3550 900)(-3725 900);
WIRE 16 -1 (-3725 900)(-3725 950);
WIRE 16 -1 (-3550 950)(-3725 950);
WIRE 16 -1 (-3725 950)(-3725 1000);
WIRE 16 -1 (-3550 1000)(-3725 1000);
WIRE 16 -1 (-3725 1000)(-3725 1250);
WIRE 16 -1 (-3550 1250)(-3725 1250);
WIRE 16 -1 (-3725 1250)(-3725 1300);
WIRE 16 -1 (-3550 1300)(-3725 1300);
WIRE 16 -1 (-3725 1300)(-3725 1350);
WIRE 16 -1 (-3550 1350)(-3725 1350);
WIRE 16 -1 (-3725 1350)(-3725 1600);
WIRE 16 -1 (-3550 1600)(-3725 1600);
WIRE 16 -1 (-3725 1600)(-3725 1650);
WIRE 16 -1 (-3550 1650)(-3725 1650);
WIRE 16 -1 (-3725 1650)(-3725 1700);
WIRE 16 -1 (-3550 1700)(-3725 1700);
WIRE 16 -1 (-3725 1700)(-3725 1950);
WIRE 16 -1 (-3550 1950)(-3725 1950);
WIRE 16 -1 (-3725 1950)(-3725 2000);
WIRE 16 -1 (-3550 2000)(-3725 2000);
WIRE 16 -1 (-3725 2000)(-3725 2050);
WIRE 16 -1 (-3550 2050)(-3725 2050);
WIRE 16 -1 (-3725 2050)(-3725 2300);
WIRE 16 -1 (-3550 2300)(-3725 2300);
WIRE 16 -1 (-3725 2300)(-3725 2350);
WIRE 16 -1 (-3550 2350)(-3725 2350);
WIRE 16 -1 (-3725 2350)(-3725 2400);
WIRE 16 -1 (-3550 2400)(-3725 2400);
WIRE 16 -1 (-3725 2400)(-3725 2650);
WIRE 16 -1 (-3550 2650)(-3725 2650);
WIRE 16 -1 (-4925 2650)(-3725 2650);
WIRE 16 -1 (-4925 3000)(-4925 2650);
WIRE 16 -1 (-2300 1300)(-2300 1250);
WIRE 16 -1 (-2750 1300)(-2300 1300);
WIRE 16 -1 (-2300 1350)(-2300 1300);
WIRE 16 -1 (-2300 1250)(-2750 1250);
WIRE 16 -1 (-2750 1350)(-2300 1350);
WIRE 16 -1 (-2300 1600)(-2300 1350);
WIRE 16 -1 (-2750 1600)(-2300 1600);
WIRE 16 -1 (-2300 1600)(-2300 1650);
WIRE 16 -1 (-2750 1650)(-2300 1650);
WIRE 16 -1 (-2300 1650)(-2300 1700);
WIRE 16 -1 (-2750 1700)(-2300 1700);
WIRE 16 -1 (-2300 1700)(-2300 1950);
WIRE 16 -1 (-2750 1950)(-2300 1950);
WIRE 16 -1 (-2300 1950)(-2300 2000);
WIRE 16 -1 (-2750 2000)(-2300 2000);
WIRE 16 -1 (-2300 2000)(-2300 2050);
WIRE 16 -1 (-2750 2050)(-2300 2050);
WIRE 16 -1 (-2300 2050)(-2300 2300);
WIRE 16 -1 (-2750 2300)(-2300 2300);
WIRE 16 -1 (-2300 2300)(-2300 2350);
WIRE 16 -1 (-2750 2350)(-2300 2350);
WIRE 16 -1 (-2300 2350)(-2300 2400);
WIRE 16 -1 (-2750 2400)(-2300 2400);
WIRE 16 -1 (-2300 2400)(-2300 2650);
WIRE 16 -1 (-2750 2650)(-2300 2650);
WIRE 16 -1 (-2300 2650)(-2300 2700);
WIRE 16 -1 (-2750 2700)(-2300 2700);
WIRE 16 -1 (-2300 2700)(-2300 2750);
WIRE 16 -1 (-2750 2750)(-2300 2750);
WIRE 16 -1 (-2300 2750)(-2300 3000);
WIRE 16 -1 (-2750 3000)(-2300 3000);
WIRE 16 -1 (-2300 3000)(-2300 3050);
WIRE 16 -1 (-2750 3050)(-2300 3050);
WIRE 16 -1 (-2300 3050)(-2300 3100);
WIRE 16 -1 (-2750 3100)(-2300 3100);
WIRE 16 -1 (-2300 3100)(-2300 3350);
WIRE 16 -1 (-2750 3350)(-2300 3350);
WIRE 16 -1 (-2300 3350)(-2300 3400);
WIRE 16 -1 (-2750 3400)(-2300 3400);
WIRE 16 -1 (-2300 3400)(-2300 3450);
WIRE 16 -1 (-2750 3450)(-2300 3450);
WIRE 16 -1 (-2300 3450)(-2300 3700);
WIRE 16 -1 (-2750 3700)(-2300 3700);
WIRE 16 -1 (-2300 3700)(-2300 3750);
WIRE 16 -1 (-2750 3750)(-2300 3750);
WIRE 16 -1 (-2300 3750)(-2300 3800);
WIRE 16 -1 (-2750 3800)(-2300 3800);
WIRE 16 -1 (-2300 3800)(-2300 3875);
WIRE 16 -1 (-600 3150)(-600 3025);
WIRE 16 -1 (-600 3025)(-1025 3025);
WIRE 16 -1 (-1025 3025)(-1025 3150);
WIRE 16 -1 (-1025 2950)(-1025 3025);
WIRE 16 -1 (-600 3350)(-600 3475);
WIRE 16 -1 (-600 3475)(-1025 3475);
WIRE 16 -1 (-1025 3350)(-1025 3475);
WIRE 16 -1 (-1025 3475)(-1025 3600);
WIRE 16 -1 (-6950 425)(-8175 425);
FORCEPROP 2 LAST SIG_NAME VR_PVCCIOMCP_CPU0_XADDR1
J 0
(-7715 440);
DISPLAY 0.617021 (-7715 440);
PAINT ORANGE (-7715 440);
FORCEPROP 2 LASTPROP $XRERR UNIQUE?
J 0
(-7955 440);
DISPLAY 0.638298 (-7955 440);
PAINT MONO (-7955 440);
DISPLAY INVISIBLE (-7955 440);
WIRE 16 -1 (-8175 225)(-8175 425);
WIRE 16 -1 (-7825 375)(-6950 375);
FORCEPROP 2 LAST SIG_NAME VR_PVCCMCP_CPU0_XADDR2
J 0
(-7715 390);
DISPLAY 0.617021 (-7715 390);
PAINT ORANGE (-7715 390);
FORCEPROP 2 LASTPROP $XRERR UNIQUE?
J 0
(-7955 390);
DISPLAY 0.638298 (-7955 390);
PAINT MONO (-7955 390);
DISPLAY INVISIBLE (-7955 390);
WIRE 16 -1 (-7825 375)(-7825 200);
WIRE 16 -1 (-7950 1125)(-6950 1125);
FORCEPROP 2 LAST SIG_NAME VSENSE_PVCCIOMCP_CPU0_SKT_VSEN
J 0
(-7960 1135);
DISPLAY 0.617021 (-7960 1135);
PAINT ORANGE (-7960 1135);
WIRE 16 -1 (-7950 1075)(-6950 1075);
FORCEPROP 2 LAST SIG_NAME VSENSE_PVCCIOMCP_CPU0_SKT_VRTN
J 0
(-7960 1085);
DISPLAY 0.617021 (-7960 1085);
PAINT ORANGE (-7960 1085);
WIRE 16 -1 (-8075 3575)(-6950 3575);
FORCEPROP 2 LAST SIG_NAME FM_CPU0_VRM_322M_156M_OSC_EN
J 0
(-8050 3585);
DISPLAY 0.617021 (-8050 3585);
PAINT ORANGE (-8050 3585);
WIRE 16 -1 (-6150 625)(-5325 625);
FORCEPROP 0 LAST SIG_NAME SVID_CLK0_CPU0_R
J 0
(-6000 635);
DISPLAY 0.617021 (-6000 635);
PAINT ORANGE (-6000 635);
WIRE 16 -1 (-6150 1325)(-5350 1325);
FORCEPROP 2 LAST SIG_NAME SMB_VR_STBY_LVC3_SCL
J 0
(-6040 1340);
DISPLAY 0.617021 (-6040 1340);
PAINT ORANGE (-6040 1340);
WIRE 16 -1 (-6150 1275)(-5350 1275);
FORCEPROP 2 LAST SIG_NAME SMB_VR_STBY_LVC3_SDA
J 0
(-6040 1290);
DISPLAY 0.617021 (-6040 1290);
PAINT ORANGE (-6040 1290);
WIRE 16 -1 (-6150 2025)(-5425 2025);
FORCEPROP 2 LAST SIG_NAME FM_PVCCIOMCP_CPU0_EN
J 0
(-5975 2035);
DISPLAY 0.617021 (-5975 2035);
PAINT ORANGE (-5975 2035);
WIRE 16 -1 (-6150 1975)(-5400 1975);
FORCEPROP 2 LAST SIG_NAME PWRGD_PVCCIOMCP_CPU0
J 0
(-5990 1990);
DISPLAY 0.617021 (-5990 1990);
PAINT ORANGE (-5990 1990);
WIRE 16 -1 (-6150 2325)(-5400 2325);
FORCEPROP 2 LAST SIG_NAME PWRGD_P1V8MCP_CPU0
J 0
(-5990 2340);
DISPLAY 0.617021 (-5990 2340);
PAINT ORANGE (-5990 2340);
WIRE 16 -1 (-6150 2375)(-5400 2375);
FORCEPROP 2 LAST SIG_NAME FM_P1V8MCP_CPU0_EN
J 0
(-6000 2385);
DISPLAY 0.617021 (-6000 2385);
PAINT ORANGE (-6000 2385);
WIRE 16 -1 (-6150 975)(-5300 975);
FORCEPROP 2 LAST SIG_NAME SVID_ALERT0_CPU0_R_N
J 0
(-6025 985);
DISPLAY 0.617021 (-6025 985);
PAINT ORANGE (-6025 985);
WIRE 16 -1 (-6150 475)(-5350 475);
FORCEPROP 2 LAST SIG_NAME PWRGD_PVCCMCP_CPU0
J 0
(-5990 490);
DISPLAY 0.617021 (-5990 490);
PAINT ORANGE (-5990 490);
WIRE 16 -1 (-6150 525)(-5350 525);
FORCEPROP 2 LAST SIG_NAME FM_PVCCMCP_CPU0_EN
J 0
(-6000 535);
DISPLAY 0.617021 (-6000 535);
PAINT ORANGE (-6000 535);
WIRE 16 -1 (-6150 375)(-5375 375);
FORCEPROP 2 LAST SIG_NAME SVID_DIO1_CPU0_R
J 0
(-6000 385);
DISPLAY 0.617021 (-6000 385);
PAINT ORANGE (-6000 385);
WIRE 16 -1 (-6150 425)(-5375 425);
FORCEPROP 0 LAST SIG_NAME SVID_CLK1_CPU0_R
J 0
(-6000 435);
DISPLAY 0.617021 (-6000 435);
PAINT ORANGE (-6000 435);
WIRE 16 -1 (-6150 575)(-5325 575);
FORCEPROP 2 LAST SIG_NAME SVID_DIO0_CPU0_R
J 0
(-6000 585);
DISPLAY 0.617021 (-6000 585);
PAINT ORANGE (-6000 585);
WIRE 16 -1 (-6150 925)(-5300 925);
FORCEPROP 2 LAST SIG_NAME SVID_ALERT1_CPU0_R_N
J 0
(-6025 935);
DISPLAY 0.617021 (-6025 935);
PAINT ORANGE (-6025 935);
WIRE 16 -1 (-3550 2200)(-4800 2200);
FORCEPROP 2 LAST SIG_NAME CLK_322M_156M_CPU0_OSC_VRM_DP
J 0
(-4760 2210);
DISPLAY 0.617021 (-4760 2210);
PAINT ORANGE (-4760 2210);
WIRE 16 -1 (-3550 2150)(-4825 2150);
FORCEPROP 2 LAST SIG_NAME CLK_322M_156M_CPU0_OSC_VRM_DN
J 0
(-4785 2160);
DISPLAY 0.617021 (-4785 2160);
PAINT ORANGE (-4785 2160);
WIRE 16 -1 (-4600 2750)(-3550 2750);
FORCEPROP 2 LAST SIG_NAME VSENSE_PVCCMCP_CPU0_SKT_VSEN
J 0
(-4615 2770);
DISPLAY 0.617021 (-4615 2770);
PAINT ORANGE (-4615 2770);
WIRE 16 -1 (-4600 2700)(-3550 2700);
FORCEPROP 2 LAST SIG_NAME VSENSE_PVCCMCP_CPU0_SKT_VRTN
J 0
(-4615 2720);
DISPLAY 0.617021 (-4615 2720);
PAINT ORANGE (-4615 2720);
WIRE 16 -1 (-3550 3300)(-4050 3300);
WIRE 16 -1 (-4050 3300)(-4050 3475);
WIRE 16 -1 (-4050 3475)(-4950 3475);
FORCEPROP 2 LAST SIG_NAME VSENSE_P1V8MCP_CPU0_SKT_VRTN
J 0
(-4940 3495);
DISPLAY 0.617021 (-4940 3495);
PAINT ORANGE (-4940 3495);
WIRE 16 -1 (-3550 3650)(-4050 3650);
WIRE 16 -1 (-4050 3650)(-4050 3550);
WIRE 16 -1 (-4950 3550)(-4050 3550);
FORCEPROP 2 LAST SIG_NAME VSENSE_P1V8MCP_CPU0_SKT_VSEN
J 0
(-4965 3570);
DISPLAY 0.617021 (-4965 3570);
PAINT ORANGE (-4965 3570);
DOT 1 (-2150 650);
DOT 1 (-2150 600);
DOT 1 (-2150 550);
DOT 1 (-2150 500);
DOT 1 (-2150 400);
DOT 1 (-2150 450);
DOT 1 (-2150 750);
DOT 1 (-2300 1350);
DOT 1 (-2300 1300);
DOT 1 (-2300 1600);
DOT 1 (-3975 1450);
DOT 1 (-3975 1800);
DOT 1 (-7975 -125);
DOT 1 (-1275 2050);
DOT 1 (-1275 2475);
DOT 1 (-5725 3775);
DOT 1 (-5725 3725);
DOT 1 (-6025 3525);
DOT 1 (-6025 3425);
DOT 1 (-6025 3375);
DOT 1 (-6025 3225);
DOT 1 (-6025 3325);
DOT 1 (-6025 3275);
DOT 1 (-6025 3175);
DOT 1 (-5775 3075);
DOT 1 (-5450 2225);
DOT 1 (-5450 2175);
DOT 1 (-5450 2125);
DOT 1 (-5775 3025);
DOT 1 (-6025 2875);
DOT 1 (-6025 2925);
DOT 1 (-6025 2825);
DOT 1 (-6025 2725);
DOT 1 (-6025 2625);
DOT 1 (-6025 2575);
DOT 1 (-6025 2675);
DOT 1 (-6025 2525);
DOT 1 (-6025 2475);
DOT 1 (-6025 2275);
DOT 1 (-5350 1625);
DOT 1 (-5450 1875);
DOT 1 (-5450 1825);
DOT 1 (-5450 1575);
DOT 1 (-5450 1775);
DOT 1 (-5450 1475);
DOT 1 (-5450 1425);
DOT 1 (-5450 1175);
DOT 1 (-5450 1225);
DOT 1 (-5450 1125);
DOT 1 (-5450 1075);
DOT 1 (-6025 1925);
DOT 1 (-6025 1675);
DOT 1 (-5450 875);
DOT 1 (-5450 825);
DOT 1 (-5450 775);
DOT 1 (-7175 3725);
DOT 1 (-7175 3775);
DOT 1 (-7175 3425);
DOT 1 (-7175 3375);
DOT 1 (-7375 3225);
DOT 1 (-7375 3175);
DOT 1 (-7175 3075);
DOT 1 (-7175 3025);
DOT 1 (-7375 2975);
DOT 1 (-7375 2925);
DOT 1 (-7375 2875);
DOT 1 (-7375 2825);
DOT 1 (-7175 2675);
DOT 1 (-7175 2725);
DOT 1 (-7375 2625);
DOT 1 (-7375 2575);
DOT 1 (-7175 2325);
DOT 1 (-7375 2475);
DOT 1 (-7375 2525);
DOT 1 (-7375 2225);
DOT 1 (-7375 2275);
DOT 1 (-7375 2175);
DOT 1 (-7375 2125);
DOT 1 (-7075 1175);
DOT 1 (-7075 975);
DOT 1 (-7075 925);
DOT 1 (-7075 875);
DOT 1 (-7075 775);
DOT 1 (-7075 625);
DOT 1 (-7075 525);
DOT 1 (-7175 2025);
DOT 1 (-7175 1975);
DOT 1 (-7375 1925);
DOT 1 (-7375 1875);
DOT 1 (-7375 1825);
DOT 1 (-7175 1625);
DOT 1 (-7175 1675);
DOT 1 (-7375 1575);
DOT 1 (-7375 1775);
DOT 1 (-7175 1325);
DOT 1 (-7375 1525);
DOT 1 (-7375 1475);
DOT 1 (-7375 1425);
DOT 1 (-1025 3475);
DOT 1 (-1025 3025);
DOT 1 (-900 1300);
DOT 1 (-900 875);
DOT 1 (-1450 1275);
DOT 1 (-1450 850);
DOT 1 (-5450 1525);
DOT 1 (-6025 3575);
DOT 1 (-2300 3750);
DOT 1 (-2300 3800);
DOT 1 (-2150 3600);
DOT 1 (-2150 3550);
DOT 1 (-2300 3700);
DOT 1 (-2150 3300);
DOT 1 (-2150 3250);
DOT 1 (-2300 3400);
DOT 1 (-2300 3450);
DOT 1 (-2300 3350);
DOT 1 (-2150 3200);
DOT 1 (-2300 3100);
DOT 1 (-2300 3050);
DOT 1 (-2300 3000);
DOT 1 (-2150 2950);
DOT 1 (-2150 2900);
DOT 1 (-2150 2850);
DOT 1 (-2300 2750);
DOT 1 (-2150 2600);
DOT 1 (-2150 2500);
DOT 1 (-2150 2550);
DOT 1 (-2300 2650);
DOT 1 (-2300 2700);
DOT 1 (-2150 2250);
DOT 1 (-2300 2350);
DOT 1 (-2300 2400);
DOT 1 (-2300 2300);
DOT 1 (-3725 3750);
DOT 1 (-3725 3800);
DOT 1 (-3725 3700);
DOT 1 (-3900 3550);
DOT 1 (-3900 3600);
DOT 1 (-3725 3400);
DOT 1 (-3725 3450);
DOT 1 (-3725 3350);
DOT 1 (-3900 3250);
DOT 1 (-3725 3100);
DOT 1 (-3725 3050);
DOT 1 (-3725 2650);
DOT 1 (-3725 2350);
DOT 1 (-3725 2400);
DOT 1 (-3725 2300);
DOT 1 (-3975 2500);
DOT 1 (-3975 2550);
DOT 1 (-3975 2250);
DOT 1 (-2150 2200);
DOT 1 (-2150 2150);
DOT 1 (-2300 2050);
DOT 1 (-2300 2000);
DOT 1 (-2300 1950);
DOT 1 (-2150 1850);
DOT 1 (-2150 1900);
DOT 1 (-2150 1800);
DOT 1 (-2300 1700);
DOT 1 (-2150 1550);
DOT 1 (-2150 1500);
DOT 1 (-2150 1450);
DOT 1 (-2300 1650);
DOT 1 (-2150 1200);
DOT 1 (-2150 1150);
DOT 1 (-2150 1100);
DOT 1 (-2150 1000);
DOT 1 (-2150 950);
DOT 1 (-2150 900);
DOT 1 (-2150 850);
DOT 1 (-2150 800);
DOT 1 (-3725 2000);
DOT 1 (-3725 2050);
DOT 1 (-3725 1950);
DOT 1 (-3725 1700);
DOT 1 (-3975 1850);
DOT 1 (-3975 1900);
DOT 1 (-3725 1650);
DOT 1 (-3725 1600);
DOT 1 (-3725 1350);
DOT 1 (-3725 1300);
DOT 1 (-3725 1250);
DOT 1 (-3975 1550);
DOT 1 (-3975 1500);
DOT 1 (-3975 1200);
DOT 1 (-3725 950);
DOT 1 (-3725 1000);
DOT 1 (-3725 900);
DOT 1 (-3975 1150);
DOT 1 (-3975 1100);
DOT 1 (-3975 850);
DOT 1 (-3975 800);
DOT 1 (-3975 750);
DOT 1 (-3725 600);
DOT 1 (-3725 650);
DOT 1 (-3975 500);
DOT 1 (-3975 450);
DOT 1 (-3975 400);
DOT 1 (-7175 2375);
DOT 1 (-7375 3325);
DOT 1 (-7375 3275);
DOT 1 (-7075 725);
DOT 1 (-7075 575);
DOT 1 (-7075 825);
DOT 1 (-7075 800);
DOT 1 (-3975 2600);
DOT 1 (-3975 2900);
DOT 1 (-3975 2850);
FORCENOTE
SMBUS ADDRESS: VCCMCP 0X98, VCCIOMCP/P1V8MCP 0XC4 
(-7550 -175) 0;
DISPLAY LEFT (-7550 -175);
DISPLAY 1.021277 (-7550 -175);
PAINT PURPLE (-7550 -175);
FORCENOTE
DEBUG ONLY
(-5927 4081) 0;
DISPLAY LEFT (-5927 4081);
DISPLAY 3.936170 (-5927 4081);
PAINT PURPLE (-5927 4081);
QUIT
